G04*
G04 #@! TF.GenerationSoftware,Altium Limited,Altium Designer,23.6.0 (18)*
G04*
G04 Layer_Physical_Order=1*
G04 Layer_Color=255*
%FSLAX44Y44*%
%MOMM*%
G71*
G04*
G04 #@! TF.SameCoordinates,0D6CC9A4-690D-4EF8-AA6E-9FB67146BD04*
G04*
G04*
G04 #@! TF.FilePolarity,Positive*
G04*
G01*
G75*
%ADD12C,0.5000*%
%ADD16R,6.9000X10.4500*%
%ADD17R,2.5500X1.0500*%
%ADD18R,1.5000X1.0000*%
%ADD19R,0.4500X0.4500*%
%ADD20R,1.2500X0.8500*%
%ADD21R,0.6500X1.2500*%
G04:AMPARAMS|DCode=22|XSize=2.3mm|YSize=1.2mm|CornerRadius=0.36mm|HoleSize=0mm|Usage=FLASHONLY|Rotation=90.000|XOffset=0mm|YOffset=0mm|HoleType=Round|Shape=RoundedRectangle|*
%AMROUNDEDRECTD22*
21,1,2.3000,0.4800,0,0,90.0*
21,1,1.5800,1.2000,0,0,90.0*
1,1,0.7200,0.2400,0.7900*
1,1,0.7200,0.2400,-0.7900*
1,1,0.7200,-0.2400,-0.7900*
1,1,0.7200,-0.2400,0.7900*
%
%ADD22ROUNDEDRECTD22*%
G04:AMPARAMS|DCode=23|XSize=2.8mm|YSize=1.2mm|CornerRadius=0.36mm|HoleSize=0mm|Usage=FLASHONLY|Rotation=90.000|XOffset=0mm|YOffset=0mm|HoleType=Round|Shape=RoundedRectangle|*
%AMROUNDEDRECTD23*
21,1,2.8000,0.4800,0,0,90.0*
21,1,2.0800,1.2000,0,0,90.0*
1,1,0.7200,0.2400,1.0400*
1,1,0.7200,0.2400,-1.0400*
1,1,0.7200,-0.2400,-1.0400*
1,1,0.7200,-0.2400,1.0400*
%
%ADD23ROUNDEDRECTD23*%
%ADD24R,2.7000X1.1500*%
%ADD25R,0.6200X0.5700*%
%ADD26R,0.4400X0.4200*%
%ADD27R,3.4000X2.7000*%
%ADD28C,1.5000*%
%ADD29R,2.2300X1.8000*%
%ADD30R,1.6500X1.3000*%
%ADD31R,0.9500X1.0000*%
%ADD32R,1.0000X0.9500*%
%ADD33R,0.6200X0.6000*%
%ADD34R,1.3000X1.6500*%
%ADD35R,0.6000X0.6200*%
%ADD36R,0.5700X0.6200*%
G04:AMPARAMS|DCode=37|XSize=0.57mm|YSize=0.62mm|CornerRadius=0mm|HoleSize=0mm|Usage=FLASHONLY|Rotation=45.000|XOffset=0mm|YOffset=0mm|HoleType=Round|Shape=Rectangle|*
%AMROTATEDRECTD37*
4,1,4,0.0177,-0.4207,-0.4207,0.0177,-0.0177,0.4207,0.4207,-0.0177,0.0177,-0.4207,0.0*
%
%ADD37ROTATEDRECTD37*%

%ADD38R,0.4200X0.4400*%
%ADD68C,0.1020*%
%ADD69C,0.1016*%
%ADD70C,1.0000*%
%ADD71C,0.3810*%
%ADD72C,0.4000*%
%ADD73C,0.3000*%
%ADD74C,0.2540*%
%ADD75C,0.6000*%
%ADD76R,2.0200X2.0200*%
%ADD77C,2.0200*%
%ADD78C,2.0900*%
%ADD79C,5.3000*%
%ADD80C,0.6000*%
G36*
X486165Y502652D02*
X484350Y501259D01*
X482427Y498753D01*
X481218Y495834D01*
X480805Y492701D01*
X481218Y489568D01*
X482427Y486649D01*
X484350Y484142D01*
X486857Y482219D01*
X489776Y481010D01*
X492909Y480597D01*
X496041Y481010D01*
X498960Y482219D01*
X501467Y484142D01*
X502652Y485686D01*
X503922Y485255D01*
X503922Y22072D01*
X502652Y21641D01*
X501036Y23746D01*
X498529Y25670D01*
X495610Y26879D01*
X492478Y27291D01*
X489345Y26879D01*
X486426Y25670D01*
X483919Y23746D01*
X481996Y21240D01*
X480786Y18320D01*
X480374Y15188D01*
X480786Y12055D01*
X481996Y9136D01*
X483919Y6629D01*
X485588Y5348D01*
X485157Y4078D01*
X4919Y4078D01*
X4078Y5042D01*
X4078Y317251D01*
X4154Y317432D01*
X4262Y317577D01*
X4322Y317640D01*
X5215Y318193D01*
X5324Y318198D01*
X5430Y318172D01*
X5678Y318162D01*
X5720Y318150D01*
X5887Y318136D01*
X5900Y318137D01*
X5912Y318134D01*
X6000Y318145D01*
X6234Y318132D01*
X6310Y318143D01*
X6323Y318142D01*
X6399Y318151D01*
X6474Y318136D01*
X11833Y318122D01*
X12158Y318114D01*
X12171Y255762D01*
X12166Y255612D01*
X12178Y255536D01*
X12173Y255424D01*
X12185Y255351D01*
X12172Y255278D01*
X12179Y255035D01*
X12196Y254959D01*
X12190Y254846D01*
X12183Y254822D01*
X12187Y254792D01*
X12185Y254753D01*
X12170Y254630D01*
X12189Y254559D01*
X12185Y254486D01*
X12199Y254389D01*
X12200Y254386D01*
X12207Y254174D01*
X12288Y253834D01*
X12352Y253490D01*
X12380Y253421D01*
X12386Y253410D01*
X12389Y253397D01*
X12517Y253206D01*
X12531Y253158D01*
X12621Y253050D01*
X12814Y252754D01*
X12824Y252746D01*
X12831Y252736D01*
X12887Y252680D01*
X12972Y252623D01*
X13037Y252544D01*
X13113Y252482D01*
X13341Y252360D01*
X13550Y252209D01*
X13689Y252175D01*
X13816Y252108D01*
X14072Y252083D01*
X14323Y252022D01*
X14670Y252008D01*
X14704Y252014D01*
X15049Y251970D01*
X15068Y251976D01*
X15089Y251974D01*
X15165Y251981D01*
X15180Y251985D01*
X15236Y251973D01*
X15307Y251971D01*
X15317Y251970D01*
X15328Y251971D01*
X15520Y251966D01*
X15600Y251980D01*
X15644Y251975D01*
X15708Y251982D01*
X15773Y251975D01*
X15911Y251989D01*
X15915Y251991D01*
X15985Y251994D01*
X16038Y251991D01*
X16063Y251984D01*
X16093Y251988D01*
X16135Y251986D01*
X16232Y252000D01*
X16250Y252006D01*
X16322Y251994D01*
X16710Y252008D01*
X17051Y252089D01*
X17395Y252153D01*
X17464Y252180D01*
X17475Y252187D01*
X17487Y252190D01*
X17808Y252404D01*
X18131Y252614D01*
X18138Y252625D01*
X18149Y252632D01*
X18246Y252729D01*
X18253Y252740D01*
X18263Y252747D01*
X18473Y253069D01*
X18688Y253391D01*
X18690Y253403D01*
X18697Y253414D01*
X18725Y253483D01*
X18788Y253824D01*
X18869Y254162D01*
X18882Y254499D01*
X18883Y254502D01*
X18883Y254512D01*
X18883Y254522D01*
X18882Y254531D01*
X18878Y254615D01*
X18885Y254666D01*
X18883Y254709D01*
X18890Y254776D01*
X18914Y254865D01*
X18901Y254971D01*
X18904Y254986D01*
X18911Y255201D01*
X18901Y255264D01*
X18911Y255328D01*
X18905Y255547D01*
X18912Y255585D01*
X18912Y255667D01*
X18914Y255681D01*
X18912Y255688D01*
X18913Y258983D01*
X18920Y259053D01*
X19117Y259493D01*
X19317Y259741D01*
X19371Y259797D01*
X19910Y260224D01*
X20138Y260231D01*
X20145Y260233D01*
X20238Y260220D01*
X20295Y260224D01*
X26287Y260217D01*
X26328Y260225D01*
X26355Y260223D01*
X26361Y260223D01*
X26367Y260222D01*
X26467Y260234D01*
X26477Y260232D01*
X26665Y260225D01*
X26730Y260236D01*
X26795Y260224D01*
X26876Y260226D01*
X26894Y260222D01*
X26946Y260228D01*
X27052Y260231D01*
X27072Y260236D01*
X27183Y260222D01*
X27261Y260243D01*
X27301Y260240D01*
X27446Y260222D01*
X27486Y260233D01*
X27527Y260229D01*
X27589Y260236D01*
X27617Y260245D01*
X27907Y260262D01*
X28124Y260318D01*
X28347Y260337D01*
X28444Y260364D01*
X28549Y260418D01*
X28665Y260441D01*
X28856Y260569D01*
X28904Y260584D01*
X28958Y260628D01*
X29152Y260728D01*
X29228Y260818D01*
X29326Y260883D01*
X29382Y260939D01*
X29439Y261024D01*
X29518Y261089D01*
X29580Y261166D01*
X29691Y261373D01*
X29834Y261560D01*
X29876Y261721D01*
X29954Y261868D01*
X29977Y262102D01*
X30037Y262330D01*
X30051Y262552D01*
X30048Y262573D01*
X30050Y262585D01*
X30046Y262626D01*
X30044Y262705D01*
X30062Y262852D01*
X30089Y263011D01*
X30082Y263240D01*
X30079Y263253D01*
X30092Y263355D01*
X30084Y263480D01*
X30095Y263551D01*
X30090Y263682D01*
X30094Y265819D01*
X34557Y265814D01*
X35477Y265059D01*
X35505Y264130D01*
X35521Y264059D01*
X35514Y263988D01*
X35528Y263849D01*
X35625Y263531D01*
X35678Y263306D01*
X35689Y263243D01*
X35698Y263218D01*
X35701Y263208D01*
X35710Y263187D01*
X35723Y263153D01*
X35732Y263140D01*
X35735Y263132D01*
X35744Y263119D01*
X35752Y263082D01*
X35794Y262985D01*
X35828Y262935D01*
X35844Y262876D01*
X35858Y262848D01*
X36058Y262590D01*
X36240Y262319D01*
X36278Y262280D01*
X36287Y262265D01*
X36302Y262253D01*
X36323Y262221D01*
X36386Y262159D01*
X36418Y262138D01*
X36429Y262123D01*
X36444Y262114D01*
X36483Y262076D01*
X36525Y262048D01*
X36531Y262041D01*
X36553Y262027D01*
X36569Y262005D01*
X36802Y261857D01*
X37013Y261694D01*
X37040Y261680D01*
X37094Y261665D01*
X37193Y261599D01*
X37219Y261594D01*
X37241Y261580D01*
X37295Y261559D01*
X37406Y261512D01*
X37566Y261478D01*
X37714Y261408D01*
X37770Y261394D01*
X37973Y261384D01*
X38170Y261335D01*
X38621Y261314D01*
X38695Y261325D01*
X38788Y261306D01*
X38899Y261304D01*
X38901Y261304D01*
X38902Y261304D01*
X39214Y261299D01*
X39535Y261286D01*
X39586Y261294D01*
X39636Y261285D01*
X41065Y261298D01*
X41132Y261313D01*
X41201Y261304D01*
X41521Y261241D01*
X42452Y260712D01*
X42538Y260623D01*
X42568Y260578D01*
X42584Y260519D01*
X42598Y260491D01*
X42626Y260455D01*
X42656Y260383D01*
X42711Y260300D01*
X42840Y260171D01*
X42943Y260016D01*
X42958Y259991D01*
X42963Y259986D01*
X42980Y259961D01*
X43056Y259885D01*
X43081Y259868D01*
X43086Y259862D01*
X43101Y259854D01*
X43139Y259815D01*
X43241Y259748D01*
X43253Y259731D01*
X43344Y259673D01*
X43486Y259537D01*
X43563Y259488D01*
X43720Y259427D01*
X43801Y259373D01*
X43826Y259368D01*
X43925Y259306D01*
X43967Y259290D01*
X44044Y259255D01*
X44396Y259176D01*
X44745Y259083D01*
X44967Y259070D01*
X44999Y259074D01*
X45099Y259052D01*
X45862Y259038D01*
X45867Y259039D01*
X45944Y259024D01*
X49723Y259031D01*
X49746Y259036D01*
X49770Y259032D01*
X50325Y259045D01*
X50348Y259051D01*
X50371Y259047D01*
X50808Y259068D01*
X51004Y259117D01*
X51205Y259126D01*
X51261Y259140D01*
X51429Y259220D01*
X51447Y259224D01*
X51547Y259240D01*
X51605Y259261D01*
X51610Y259262D01*
X51618Y259266D01*
X51679Y259288D01*
X51704Y259303D01*
X51732Y259308D01*
X51753Y259317D01*
X51780Y259307D01*
X51878Y259262D01*
X52241Y259177D01*
X52602Y259083D01*
X52838Y259069D01*
X52866Y259073D01*
X52961Y259052D01*
X53710Y259038D01*
X53715Y259039D01*
X53791Y259024D01*
X63172Y259031D01*
X63197Y259036D01*
X63221Y259032D01*
X63789Y259045D01*
X63820Y259052D01*
X63851Y259048D01*
X64232Y259069D01*
X64282Y259081D01*
X64287Y259081D01*
X64329Y259090D01*
X64409Y259086D01*
X64507Y259100D01*
X64780Y259196D01*
X64899Y259224D01*
X64999Y259240D01*
X65057Y259261D01*
X65062Y259262D01*
X65070Y259266D01*
X65131Y259289D01*
X65196Y259328D01*
X65270Y259345D01*
X65346Y259380D01*
X65584Y259551D01*
X65838Y259696D01*
X65905Y259781D01*
X65926Y259796D01*
X65956Y259814D01*
X65964Y259824D01*
X65992Y259844D01*
X66012Y259876D01*
X66034Y259899D01*
X66065Y259944D01*
X66161Y260018D01*
X66287Y260240D01*
X66444Y260443D01*
X66472Y260498D01*
X66498Y260594D01*
X66526Y260639D01*
X66539Y260656D01*
X66543Y260665D01*
X66551Y260678D01*
X66564Y260711D01*
X66608Y260809D01*
X66698Y261190D01*
X66790Y261571D01*
X66803Y261918D01*
X66801Y261933D01*
X66819Y262017D01*
X66833Y263181D01*
X66847Y263253D01*
X66842Y264913D01*
X67739Y265812D01*
X107292Y265819D01*
X107332Y265827D01*
X107373Y265821D01*
X107713Y265835D01*
X108134Y265848D01*
X108179Y265858D01*
X108225Y265853D01*
X108405Y265867D01*
X108571Y265913D01*
X108743Y265922D01*
X108799Y265936D01*
X108870Y265970D01*
X108949Y265979D01*
X109011Y266000D01*
X109030Y266011D01*
X109049Y266016D01*
X109085Y266034D01*
X109124Y266041D01*
X109193Y266069D01*
X109210Y266080D01*
X109412Y266123D01*
X109509Y266164D01*
X109565Y266203D01*
X109630Y266229D01*
X109651Y266242D01*
X109676Y266248D01*
X109773Y266289D01*
X109823Y266324D01*
X109882Y266340D01*
X109910Y266354D01*
X109947Y266383D01*
X109986Y266390D01*
X110216Y266544D01*
X110228Y266548D01*
X110256Y266562D01*
X110324Y266614D01*
X110402Y266662D01*
X110531Y266731D01*
X110581Y266772D01*
X110589Y266776D01*
X110592Y266780D01*
X110608Y266793D01*
X110631Y266822D01*
X110647Y266833D01*
X110667Y266852D01*
X110715Y266880D01*
X110741Y266914D01*
X110786Y266943D01*
X110821Y266978D01*
X110844Y267013D01*
X110854Y267018D01*
X110867Y267036D01*
X110885Y267049D01*
X110890Y267059D01*
X110925Y267082D01*
X110959Y267117D01*
X110976Y267142D01*
X110978Y267143D01*
X110998Y267168D01*
X111023Y267188D01*
X111029Y267198D01*
X111064Y267222D01*
X111085Y267243D01*
X111113Y267284D01*
X111132Y267304D01*
X111162Y267327D01*
X111171Y267342D01*
X111174Y267346D01*
X111188Y267366D01*
X111209Y267380D01*
X111271Y267442D01*
X111301Y267465D01*
X111309Y267481D01*
X111313Y267484D01*
X111327Y267505D01*
X111348Y267519D01*
X111365Y267537D01*
X111381Y267545D01*
X111403Y267575D01*
X111410Y267581D01*
X111439Y267604D01*
X111441Y267606D01*
X111466Y267623D01*
X111486Y267644D01*
X111514Y267686D01*
X111535Y267706D01*
X111564Y267729D01*
X111566Y267731D01*
X111590Y267748D01*
X111611Y267769D01*
X111645Y267820D01*
X111689Y267854D01*
X111716Y267901D01*
X111743Y267928D01*
X111758Y267950D01*
X111779Y267965D01*
X111869Y268108D01*
X111918Y268161D01*
X111959Y268231D01*
X111974Y268271D01*
X111976Y268273D01*
X112039Y268349D01*
X112060Y268389D01*
X112087Y268412D01*
X112150Y268488D01*
X112263Y268702D01*
X112284Y268729D01*
X112298Y268756D01*
X112304Y268778D01*
X112310Y268790D01*
X112349Y268853D01*
X112375Y268883D01*
X112438Y268987D01*
X112450Y269019D01*
X112488Y269082D01*
X112529Y269196D01*
X112583Y269278D01*
X112610Y269348D01*
X112637Y269489D01*
X112681Y269589D01*
X112691Y269637D01*
X112717Y269678D01*
X112752Y269768D01*
X112773Y269892D01*
X112827Y270006D01*
X112841Y270061D01*
X112842Y270072D01*
X112877Y270254D01*
X112881Y270267D01*
X112887Y270310D01*
X112894Y270347D01*
X112979Y270615D01*
X112992Y270726D01*
X113018Y270934D01*
X113013Y270996D01*
X113029Y271057D01*
X113043Y271276D01*
X113049Y271300D01*
X113143Y271619D01*
X113157Y271772D01*
X113136Y271969D01*
X113144Y272008D01*
X113117Y272153D01*
X113093Y272493D01*
X113073Y272569D01*
X113039Y272636D01*
X113028Y272788D01*
X113014Y272841D01*
X113018Y272896D01*
X113006Y272992D01*
X112986Y273166D01*
X112945Y273297D01*
X112938Y273435D01*
X112924Y273490D01*
X112871Y273604D01*
X112849Y273729D01*
X112780Y273909D01*
X112762Y273937D01*
X112712Y274158D01*
X112657Y274282D01*
X112639Y274308D01*
X112637Y274312D01*
X112604Y274366D01*
X112604Y274368D01*
X112601Y274371D01*
X112598Y274377D01*
X112580Y274450D01*
X112546Y274527D01*
X112497Y274595D01*
X112488Y274616D01*
X112481Y274628D01*
X112479Y274641D01*
X112451Y274711D01*
X112444Y274721D01*
X112442Y274734D01*
X112376Y274832D01*
X112360Y274857D01*
X112354Y274891D01*
X112326Y274960D01*
X112319Y274971D01*
X112317Y274983D01*
X112161Y275217D01*
X112099Y275348D01*
X112072Y275372D01*
X112061Y275398D01*
X111998Y275488D01*
X111987Y275500D01*
X111952Y275560D01*
X111919Y275586D01*
X111892Y275627D01*
X111882Y275634D01*
X111875Y275645D01*
X111854Y275666D01*
X111820Y275688D01*
X111775Y275809D01*
X111695Y275894D01*
X111642Y275998D01*
X111436Y276172D01*
X111419Y276207D01*
X111307Y276309D01*
X111223Y276435D01*
X111202Y276456D01*
X110986Y276600D01*
X110868Y276708D01*
X110846Y276729D01*
X110842Y276731D01*
X110830Y276742D01*
X110754Y276770D01*
X110743Y276784D01*
X110662Y276829D01*
X110590Y276922D01*
X110526Y276959D01*
X110520Y276964D01*
X110500Y276973D01*
X110435Y277011D01*
X110303Y277131D01*
X110233Y277172D01*
X110091Y277223D01*
X110031Y277250D01*
X109890Y277337D01*
X109829Y277359D01*
X109759Y277405D01*
X109730Y277425D01*
X109720Y277430D01*
X109713Y277435D01*
X109687Y277445D01*
X109664Y277456D01*
X109649Y277464D01*
X109647Y277465D01*
X109645Y277466D01*
X109627Y277472D01*
X109578Y277495D01*
X109516Y277509D01*
X109288Y277585D01*
X109149Y277651D01*
X109090Y277666D01*
X109086Y277668D01*
X108989Y277696D01*
X108969Y277698D01*
X108806Y277779D01*
X108730Y277800D01*
X108708Y277801D01*
X108688Y277811D01*
X108632Y277825D01*
X108618Y277825D01*
X108449Y277857D01*
X108426Y277865D01*
X108337Y277878D01*
X108289Y277887D01*
X107950Y277967D01*
X107575Y277981D01*
X107554Y277978D01*
X107461Y277997D01*
X97429Y278010D01*
X96183Y278024D01*
X95646Y278054D01*
X95611Y278057D01*
X95569Y278073D01*
X95486Y278087D01*
X95421Y278085D01*
X95360Y278104D01*
X95159Y278124D01*
X95110Y278120D01*
X95000Y278147D01*
X94849Y278154D01*
X94812Y278160D01*
X94767Y278173D01*
X94667Y278233D01*
X94657Y278237D01*
X94648Y278242D01*
X94571Y278272D01*
X94516Y278294D01*
X94421Y278359D01*
X94365Y278383D01*
X94360Y278391D01*
X94283Y278467D01*
X94246Y278492D01*
X94221Y278529D01*
X93992Y278758D01*
X93971Y278772D01*
X93957Y278793D01*
X93910Y278840D01*
X93823Y279016D01*
X93761Y279069D01*
X93758Y280308D01*
X93806Y280370D01*
X93897Y280551D01*
X93972Y280648D01*
X93987Y280704D01*
X94070Y280795D01*
X94080Y280812D01*
X94266Y280933D01*
X94273Y280943D01*
X94283Y280950D01*
X94341Y281008D01*
X94373Y281018D01*
X94452Y281061D01*
X94502Y281083D01*
X94570Y281131D01*
X94650Y281157D01*
X94730Y281200D01*
X94779Y281222D01*
X94791Y281231D01*
X95245Y281241D01*
X95275Y281248D01*
X95276Y281247D01*
X112243Y281254D01*
X112305Y281266D01*
X112333Y281261D01*
X112839Y281268D01*
X112878Y281277D01*
X112918Y281271D01*
X113445Y281299D01*
X113492Y281311D01*
X113541Y281306D01*
X113680Y281320D01*
X113846Y281371D01*
X113905Y281368D01*
X114043Y281389D01*
X114105Y281396D01*
X114237Y281408D01*
X114265Y281417D01*
X114295Y281414D01*
X114469Y281435D01*
X114757Y281530D01*
X115054Y281596D01*
X115143Y281636D01*
X115246Y281677D01*
X115307Y281717D01*
X115316Y281717D01*
X115372Y281731D01*
X115533Y281807D01*
X115706Y281846D01*
X115830Y281901D01*
X115852Y281917D01*
X115887Y281929D01*
X115929Y281955D01*
X115977Y281964D01*
X116268Y282159D01*
X116275Y282163D01*
X116302Y282177D01*
X116319Y282189D01*
X116367Y282218D01*
X116490Y282280D01*
X116560Y282335D01*
X116569Y282340D01*
X116571Y282343D01*
X116615Y282377D01*
X116632Y282397D01*
X116635Y282399D01*
X116681Y282434D01*
X116681Y282434D01*
X116727Y282460D01*
X116733Y282469D01*
X117037Y282666D01*
X117044Y282677D01*
X117054Y282684D01*
X117106Y282736D01*
X117122Y282744D01*
X117133Y282759D01*
X117165Y282781D01*
X117228Y282843D01*
X117249Y282875D01*
X117264Y282886D01*
X117265Y282889D01*
X117290Y282905D01*
X117491Y283106D01*
X117515Y283141D01*
X117525Y283148D01*
X117529Y283152D01*
X117554Y283169D01*
X117630Y283245D01*
X117646Y283270D01*
X117647Y283270D01*
X117649Y283271D01*
X117649Y283272D01*
X117651Y283274D01*
X117653Y283277D01*
X117660Y283286D01*
X117692Y283308D01*
X117755Y283370D01*
X117776Y283402D01*
X117791Y283413D01*
X117796Y283423D01*
X117831Y283446D01*
X117879Y283495D01*
X117902Y283529D01*
X117912Y283535D01*
X117916Y283540D01*
X117942Y283557D01*
X118018Y283633D01*
X118035Y283659D01*
X118040Y283663D01*
X118049Y283678D01*
X118101Y283731D01*
X118259Y283966D01*
X118442Y284182D01*
X118511Y284307D01*
X119694Y284588D01*
X120323Y284295D01*
X120537Y283974D01*
X120552Y283952D01*
X120586Y283868D01*
X120642Y283785D01*
X120695Y283731D01*
X120747Y283651D01*
X120758Y283644D01*
X120765Y283633D01*
X120771Y283627D01*
X120798Y283580D01*
X120894Y283505D01*
X120924Y283460D01*
X121479Y282905D01*
X121500Y282892D01*
X121514Y282871D01*
X121604Y282781D01*
X121645Y282753D01*
X121715Y282684D01*
X121744Y282664D01*
X121764Y282635D01*
X122073Y282444D01*
X122088Y282434D01*
X122134Y282399D01*
X122161Y282385D01*
X122162Y282385D01*
X122376Y282241D01*
X122411Y282235D01*
X122441Y282216D01*
X122486Y282199D01*
X122495Y282195D01*
X122496Y282194D01*
X122572Y282131D01*
X122639Y282096D01*
X122644Y282092D01*
X122697Y282061D01*
X122784Y281979D01*
X122982Y281905D01*
X123007Y281888D01*
X123043Y281881D01*
X123275Y281757D01*
X123377Y281747D01*
X123396Y281739D01*
X123444Y281728D01*
X123485Y281702D01*
X123575Y281667D01*
X123699Y281646D01*
X123813Y281592D01*
X123868Y281579D01*
X123877Y281578D01*
X123915Y281563D01*
X124039Y281542D01*
X124153Y281488D01*
X124208Y281474D01*
X124314Y281469D01*
X124414Y281434D01*
X124560Y281413D01*
X124592Y281415D01*
X124623Y281405D01*
X124755Y281391D01*
X124871Y281342D01*
X124941Y281328D01*
X125016Y281328D01*
X125088Y281305D01*
X125199Y281291D01*
X125213Y281292D01*
X125227Y281287D01*
X125414Y281267D01*
X125639Y281286D01*
X125864Y281267D01*
X126051Y281287D01*
X126065Y281292D01*
X126079Y281291D01*
X126190Y281305D01*
X126262Y281328D01*
X126337Y281328D01*
X126406Y281342D01*
X126513Y281387D01*
X126608Y281402D01*
X126647Y281407D01*
X126743Y281417D01*
X126886Y281460D01*
X127035Y281468D01*
X127090Y281481D01*
X127129Y281500D01*
X127171Y281504D01*
X127289Y281538D01*
X127340Y281565D01*
X127340D01*
X127382Y281575D01*
X127418Y281581D01*
X127430Y281585D01*
X127576Y281592D01*
X127631Y281606D01*
X127809Y281690D01*
X127999Y281737D01*
X128198Y281829D01*
X128341Y281895D01*
X128387Y281928D01*
X128396Y281931D01*
X128429Y281952D01*
X128467Y281960D01*
X128564Y282001D01*
X128652Y282062D01*
X128671Y282066D01*
X128740Y282093D01*
X128751Y282101D01*
X128764Y282103D01*
X128874Y282177D01*
X128907Y282197D01*
X128917Y282205D01*
X128996Y282258D01*
X129127Y282320D01*
X129173Y282371D01*
X129244Y282409D01*
X129279Y282425D01*
X129294Y282436D01*
X129309Y282443D01*
X129385Y282506D01*
X129398Y282522D01*
X129407Y282527D01*
X129414Y282538D01*
X129425Y282545D01*
X129430Y282551D01*
X129478Y282578D01*
X129553Y282674D01*
X129598Y282704D01*
X129688Y282794D01*
X129702Y282815D01*
X129723Y282829D01*
X129785Y282891D01*
X129814Y282914D01*
X129823Y282930D01*
X130101Y283208D01*
X130113Y283218D01*
X130122Y283228D01*
X130128Y283235D01*
X130144Y283244D01*
X130218Y283340D01*
X130263Y283370D01*
X130354Y283460D01*
X130367Y283481D01*
X130388Y283495D01*
X130450Y283557D01*
X130480Y283580D01*
X130508Y283630D01*
X130605Y283705D01*
X130632Y283753D01*
X130674Y283789D01*
X130722Y283851D01*
X130792Y283990D01*
X130953Y284174D01*
X131008Y284272D01*
X131040Y284367D01*
X131047Y284378D01*
X131064Y284397D01*
X131080Y284426D01*
X131101Y284455D01*
X131115Y284486D01*
X131119Y284494D01*
X131122Y284503D01*
X131157Y284580D01*
X131160Y284596D01*
X131200Y284651D01*
X131246Y284751D01*
X131258Y284771D01*
X131264Y284788D01*
X131283Y284831D01*
X131288Y284852D01*
X131328Y284906D01*
X131467Y285197D01*
X131533Y285459D01*
X131593Y285591D01*
X131604Y285639D01*
X131624Y285706D01*
X131671Y285790D01*
X131685Y285831D01*
X131708Y286014D01*
X131769Y286188D01*
X131783Y286285D01*
X131782Y286311D01*
X131791Y286349D01*
X131792Y286366D01*
X131794Y286370D01*
X131801Y286448D01*
X131866Y286619D01*
X131880Y286702D01*
X131877Y286787D01*
X131901Y286868D01*
X131915Y287035D01*
X131914Y287041D01*
X131916Y287048D01*
X131936Y287318D01*
X131918Y287472D01*
X131937Y287625D01*
X131909Y288000D01*
X131902Y288025D01*
X131904Y288052D01*
X131891Y288191D01*
X131837Y288365D01*
X131822Y288548D01*
X131795Y288645D01*
X131784Y288665D01*
X131737Y288823D01*
X131725Y289003D01*
X131704Y289079D01*
X131628Y289231D01*
X131621Y289263D01*
X131618Y289314D01*
X131590Y289425D01*
X131507Y289603D01*
X131481Y289706D01*
X131479Y289744D01*
X131452Y289855D01*
X131387Y289992D01*
X131357Y290141D01*
X131219Y290349D01*
X131112Y290575D01*
X131068Y290614D01*
X131055Y290640D01*
X130958Y290765D01*
X130948Y290774D01*
X130930Y290799D01*
X130923Y290813D01*
X130870Y290881D01*
X130822Y290960D01*
X130774Y291051D01*
X130770Y291063D01*
X130756Y291091D01*
X130636Y291246D01*
X130612Y291296D01*
X130561Y291342D01*
X130556Y291349D01*
X130442Y291519D01*
X130406Y291575D01*
X130404Y291576D01*
X130374Y291621D01*
X130336Y291659D01*
X130327Y291674D01*
X130312Y291686D01*
X130291Y291718D01*
X130229Y291780D01*
X130197Y291801D01*
X130191Y291809D01*
X130189Y291813D01*
X130187Y291814D01*
X130185Y291816D01*
X130183Y291818D01*
X130167Y291842D01*
X130090Y291919D01*
X130065Y291936D01*
X130061Y291941D01*
X130045Y291950D01*
X130014Y291982D01*
X129928Y292038D01*
X129863Y292118D01*
X129787Y292180D01*
X129743Y292203D01*
X129710Y292240D01*
X129559Y292311D01*
X129535Y292335D01*
X129494Y292363D01*
X129425Y292432D01*
X129298Y292516D01*
X129197Y292628D01*
X128971Y292735D01*
X128946Y292752D01*
X128920Y292783D01*
X128844Y292846D01*
X128777Y292881D01*
X128772Y292885D01*
X128675Y292941D01*
X128675Y292941D01*
X128561Y293040D01*
X128343Y293112D01*
X128142Y293220D01*
X128037Y293230D01*
X127985Y293254D01*
X127694Y293325D01*
X127633Y293366D01*
X127620Y293369D01*
X127610Y293376D01*
X127540Y293403D01*
X127403Y293429D01*
X127278Y293488D01*
X127167Y293516D01*
X127038Y293522D01*
X126993Y293537D01*
X126993Y293537D01*
X126993Y293537D01*
X126915Y293563D01*
X126806Y293576D01*
X126777Y293588D01*
X126723Y293613D01*
X126704Y293618D01*
X126698Y293621D01*
X126676Y293625D01*
X126667Y293627D01*
X126665Y293627D01*
X126628Y293634D01*
X126512Y293635D01*
X126495Y293636D01*
X126329Y293682D01*
X125878Y293717D01*
X125725Y293698D01*
X125571Y293717D01*
X125197Y293689D01*
X125171Y293682D01*
X125145Y293685D01*
X125006Y293671D01*
X124863Y293627D01*
X124714Y293620D01*
X124659Y293606D01*
X124615Y293586D01*
X124567Y293581D01*
X124534Y293571D01*
X124442Y293564D01*
X124347Y293537D01*
X124340Y293537D01*
X124284Y293523D01*
X124272Y293517D01*
X124104Y293509D01*
X123993Y293482D01*
X123856Y293417D01*
X123778Y293404D01*
X123777Y293403D01*
X123776Y293403D01*
X123729Y293386D01*
X123707Y293382D01*
X123649Y293361D01*
X123644Y293360D01*
X123636Y293356D01*
X123575Y293333D01*
X123547Y293316D01*
X123422Y293269D01*
X123303Y293224D01*
X123249Y293216D01*
X123117Y293167D01*
X123061Y293132D01*
X123034Y293122D01*
X123033Y293122D01*
X123032Y293121D01*
X122959Y293076D01*
X122876Y293045D01*
X122837Y293022D01*
X122792Y293013D01*
X122655Y292921D01*
X122637Y292913D01*
X122552Y292852D01*
X122522Y292833D01*
X122454Y292808D01*
X122385Y292766D01*
X122322Y292709D01*
X122196Y292633D01*
X122176Y292606D01*
X122175Y292606D01*
X122148Y292592D01*
X122059Y292524D01*
X122055Y292521D01*
X121732Y292311D01*
X121725Y292300D01*
X121715Y292293D01*
X121659Y292238D01*
X121617Y292210D01*
X121527Y292120D01*
X121513Y292099D01*
X121493Y292085D01*
X120876Y291468D01*
X120848Y291426D01*
X120792Y291371D01*
X120642Y291146D01*
X120464Y290941D01*
X120408Y290844D01*
X120403Y290828D01*
X120364Y290771D01*
X120339Y290714D01*
X120277Y290658D01*
X120257Y290616D01*
X120208Y290562D01*
X120167Y290493D01*
X120121Y290366D01*
X120113Y290353D01*
X119529Y290184D01*
X119381Y290173D01*
X118733Y290330D01*
X118673Y290397D01*
X118644Y290479D01*
X118602Y290548D01*
X118566Y290588D01*
X118536Y290645D01*
X118473Y290721D01*
X118449Y290741D01*
X118444Y290754D01*
X118421Y290786D01*
X118414Y290800D01*
X118379Y290845D01*
X118357Y290878D01*
X118147Y291201D01*
X118136Y291208D01*
X118129Y291219D01*
X118063Y291285D01*
X118054Y291300D01*
X118049Y291304D01*
X118032Y291329D01*
X117956Y291406D01*
X117935Y291420D01*
X117921Y291440D01*
X117874Y291488D01*
X117786Y291663D01*
X117688Y291748D01*
X117616Y291857D01*
X117443Y292030D01*
X117405Y292055D01*
X117378Y292092D01*
X117103Y292258D01*
X117103Y292259D01*
X117040Y292321D01*
X117008Y292342D01*
X116997Y292357D01*
X116982Y292366D01*
X116979Y292369D01*
X116906Y292418D01*
X116884Y292449D01*
X116862Y292464D01*
X116827Y292506D01*
X116751Y292568D01*
X116537Y292682D01*
X116510Y292703D01*
X116483Y292717D01*
X116466Y292721D01*
X116217Y292883D01*
X116171Y292902D01*
X116102Y292932D01*
X116011Y292992D01*
X115999Y292994D01*
X115988Y293001D01*
X115927Y293026D01*
X115914Y293036D01*
X115886Y293050D01*
X115833Y293064D01*
X115734Y293131D01*
X115708Y293136D01*
X115686Y293150D01*
X115644Y293166D01*
X115567Y293200D01*
X115546Y293205D01*
X115471Y293255D01*
X115458Y293258D01*
X115448Y293265D01*
X115378Y293293D01*
X115223Y293321D01*
X115079Y293386D01*
X115041Y293395D01*
X115039Y293396D01*
X114969Y293424D01*
X114713Y293472D01*
X114465Y293554D01*
X114377Y293565D01*
X114361Y293570D01*
X114353Y293575D01*
X114277Y293595D01*
X114089Y293608D01*
X114052Y293613D01*
X113766Y293680D01*
X113350Y293694D01*
X113333Y293691D01*
X113244Y293709D01*
X102843Y293723D01*
X102834Y293721D01*
X102794Y293729D01*
X102381Y293736D01*
X102321Y293749D01*
X102105Y293756D01*
X102058Y293778D01*
X102025Y293786D01*
X101903Y293854D01*
X101857Y293869D01*
X101654Y293992D01*
X101578Y294069D01*
X101557Y294082D01*
X101543Y294103D01*
X101314Y294332D01*
X101293Y294346D01*
X101280Y294366D01*
X101248Y294398D01*
X101221Y294433D01*
X101212Y294459D01*
X101170Y294529D01*
X101109Y294596D01*
X101109Y294597D01*
X101095Y294626D01*
X101088Y294643D01*
X101086Y294647D01*
X101055Y294711D01*
X101036Y294825D01*
X101035Y294833D01*
X101022Y294875D01*
X101024Y294919D01*
X101010Y295016D01*
X100975Y295116D01*
X100970Y295222D01*
X100956Y295278D01*
X100951Y295288D01*
X100952Y295301D01*
X100970Y295347D01*
X100984Y295416D01*
X100984Y295450D01*
X100996Y295481D01*
X101010Y295564D01*
X101008Y295632D01*
X101028Y295696D01*
X101041Y295827D01*
X101045Y295841D01*
X101065Y295884D01*
X101073Y295917D01*
X101084Y295933D01*
X101096Y295963D01*
X101143Y296032D01*
X101195Y296153D01*
X101327Y296362D01*
X101347Y296391D01*
X101399Y296432D01*
X101404Y296435D01*
X101727Y296645D01*
X101734Y296655D01*
X101744Y296662D01*
X101778Y296697D01*
X101825Y296719D01*
X102006Y296761D01*
X102012Y296764D01*
X102017Y296764D01*
X102073Y296778D01*
X102219Y296847D01*
X102266Y296852D01*
X102338Y296873D01*
X102364Y296875D01*
X102419Y296889D01*
X102457Y296906D01*
X102624Y296920D01*
X102641Y296925D01*
X102679Y296927D01*
X102735Y296940D01*
X103366Y296953D01*
X103409Y296962D01*
X103453Y296957D01*
X103541Y296962D01*
X103589Y296953D01*
X103624Y296960D01*
X103719Y296960D01*
X103734Y296958D01*
X103740Y296960D01*
X132595Y296973D01*
X132619Y296978D01*
X132643Y296974D01*
X133212Y296988D01*
X133244Y296995D01*
X133277Y296991D01*
X133645Y297011D01*
X133832Y297060D01*
X134024Y297069D01*
X134080Y297083D01*
X134127Y297105D01*
X134179Y297110D01*
X134213Y297121D01*
X134345Y297139D01*
X134628Y297239D01*
X134919Y297310D01*
X135117Y297403D01*
X135261Y297468D01*
X135322Y297512D01*
X135394Y297534D01*
X135474Y297578D01*
X135523Y297600D01*
X135574Y297636D01*
X135593Y297643D01*
X135645Y297676D01*
X135705Y297690D01*
X135781Y297725D01*
X135840Y297767D01*
X135843Y297768D01*
X135854Y297775D01*
X135868Y297778D01*
X135937Y297806D01*
X135948Y297813D01*
X135960Y297815D01*
X136057Y297880D01*
X136068Y297885D01*
X136152Y297940D01*
X136160Y297949D01*
X136174Y297958D01*
X136175Y297958D01*
X136203Y297972D01*
X136249Y298008D01*
X136281Y298029D01*
X136604Y298240D01*
X136709Y298246D01*
X137165Y298188D01*
X137393Y298122D01*
X137934Y297760D01*
X137953Y297665D01*
X138508Y296835D01*
X146938Y288405D01*
X147768Y287850D01*
X148747Y287655D01*
X156752D01*
X165388Y279020D01*
Y272871D01*
X148947D01*
Y241871D01*
X180690D01*
X180937Y241822D01*
X183414D01*
X192441Y232795D01*
Y160988D01*
X192636Y160009D01*
X193190Y159179D01*
X202929Y149440D01*
X203759Y148886D01*
X204738Y148691D01*
X244500D01*
X245479Y148886D01*
X246310Y149440D01*
X256065Y159196D01*
X256620Y160026D01*
X256815Y161005D01*
Y176798D01*
X257944Y177705D01*
X259933D01*
X261771Y178466D01*
X263178Y179873D01*
X263939Y181710D01*
Y183700D01*
X263178Y185537D01*
X261771Y186944D01*
X259933Y187705D01*
X257944D01*
X256106Y186944D01*
X254700Y185537D01*
X253939Y183700D01*
Y182106D01*
X252446Y180613D01*
X251917Y179822D01*
X251256Y179676D01*
X250581Y179708D01*
X250132Y180381D01*
X248826Y181687D01*
X248939Y181961D01*
Y183950D01*
X248178Y185787D01*
X246771Y187194D01*
X244933Y187955D01*
X242944D01*
X241106Y187194D01*
X239700Y185787D01*
X238939Y183950D01*
Y181961D01*
X239700Y180123D01*
X241106Y178716D01*
X242944Y177955D01*
X244933D01*
X245763Y176966D01*
Y164883D01*
X240440Y159559D01*
X207560D01*
X202059Y165060D01*
Y238610D01*
X201864Y239589D01*
X201310Y240419D01*
X192809Y248920D01*
Y314796D01*
X192614Y315775D01*
X192060Y316606D01*
X189167Y319498D01*
X189082Y319555D01*
X186947Y321690D01*
Y349071D01*
X148947D01*
Y338297D01*
X147677Y338005D01*
X147310Y338555D01*
X135309Y350555D01*
Y443648D01*
X135309Y443648D01*
X135114Y444628D01*
X134560Y445458D01*
X123059Y456959D01*
Y459198D01*
X123119Y459258D01*
X136000D01*
X136000Y459258D01*
X137222Y459143D01*
X138755Y458508D01*
X140744D01*
X142582Y459269D01*
X143989Y460676D01*
X144750Y462514D01*
Y464503D01*
X143989Y466340D01*
X142582Y467747D01*
X140744Y468508D01*
X138755D01*
X137222Y467873D01*
X136000Y467758D01*
X136000Y467758D01*
X136000Y467758D01*
X123119D01*
X123059Y467818D01*
Y471440D01*
X125180Y473561D01*
X127194Y472398D01*
X130361Y471550D01*
X133639D01*
X136805Y472398D01*
X139644Y474038D01*
X141962Y476356D01*
X143602Y479194D01*
X144450Y482361D01*
Y485639D01*
X143602Y488806D01*
X141962Y491645D01*
X139644Y493963D01*
X136805Y495602D01*
X133639Y496450D01*
X130361D01*
X127194Y495602D01*
X124355Y493963D01*
X122037Y491645D01*
X120398Y488806D01*
X119550Y485639D01*
Y482361D01*
X120398Y479194D01*
X121561Y477180D01*
X118756Y474376D01*
X118676Y474309D01*
X117137Y474270D01*
X113093Y478314D01*
X113602Y479194D01*
X114450Y482361D01*
Y485639D01*
X113602Y488806D01*
X111962Y491645D01*
X109644Y493963D01*
X106805Y495602D01*
X103639Y496450D01*
X100361D01*
X97194Y495602D01*
X94355Y493963D01*
X92037Y491645D01*
X90398Y488806D01*
X89550Y485639D01*
Y482361D01*
X90398Y479194D01*
X92037Y476356D01*
X94355Y474038D01*
X97194Y472398D01*
X100361Y471550D01*
X103639D01*
X106805Y472398D01*
X109644Y474038D01*
X109888Y474281D01*
X113441Y470728D01*
Y468318D01*
X112881Y467758D01*
X100000D01*
Y467586D01*
X71597D01*
X69995Y468250D01*
X68005D01*
X66168Y467489D01*
X64761Y466082D01*
X64000Y464245D01*
Y463003D01*
X62730Y462663D01*
X61395Y464976D01*
X58976Y467395D01*
X56014Y469105D01*
X53000Y469912D01*
Y459000D01*
X63912D01*
X63863Y459186D01*
X64017Y459366D01*
X65749Y459430D01*
X66168Y459011D01*
X68005Y458250D01*
X69995D01*
X71832Y459011D01*
X72251Y459430D01*
X100000D01*
Y459258D01*
X112881D01*
X113691Y458448D01*
Y452750D01*
X113886Y451771D01*
X114440Y450940D01*
X125691Y439690D01*
Y345971D01*
X125886Y344992D01*
X126440Y344161D01*
X137758Y332843D01*
Y308624D01*
X137731Y308588D01*
X137584Y308450D01*
X137565Y308435D01*
X136445Y308030D01*
X136365Y308081D01*
X136328Y308117D01*
X136254Y308195D01*
X136206Y308230D01*
X135984Y308330D01*
X135849Y308420D01*
X135849Y308420D01*
X135837Y308429D01*
X135792Y308455D01*
X135778Y308464D01*
X135769Y308467D01*
X135713Y308499D01*
X135641Y308522D01*
X135627Y308531D01*
X135623Y308532D01*
X135566Y308573D01*
X135414Y308642D01*
X135385Y308649D01*
X135302Y308704D01*
X135278Y308709D01*
X135275Y308711D01*
X135266Y308715D01*
X135253Y308724D01*
X135220Y308736D01*
X135122Y308781D01*
X135104Y308785D01*
X135038Y308829D01*
X135026Y308831D01*
X135015Y308838D01*
X134946Y308866D01*
X134771Y308899D01*
X134741Y308912D01*
X134722Y308917D01*
X134674Y308937D01*
X134655Y308949D01*
X134585Y308977D01*
X134479Y308997D01*
X134468Y309000D01*
X134463Y309000D01*
X134448Y309002D01*
X134322Y309062D01*
X134267Y309076D01*
X134185Y309080D01*
X134108Y309109D01*
X134024Y309123D01*
X133954Y309121D01*
X133886Y309141D01*
X133716Y309158D01*
X133666Y309165D01*
X133625Y309163D01*
X133367Y309235D01*
X133097Y309256D01*
X133075Y309253D01*
X133053Y309258D01*
X132804Y309272D01*
X132773Y309268D01*
X132743Y309275D01*
X132202Y309289D01*
X132176Y309284D01*
X132150Y309289D01*
X86620Y309303D01*
X86120Y309316D01*
X85853Y309330D01*
X85834Y309338D01*
X85800Y309346D01*
X85770Y309365D01*
X85701Y309393D01*
X85585Y309415D01*
X85480Y309467D01*
X85474Y309469D01*
X85451Y309487D01*
X85407Y309510D01*
X85374Y309547D01*
X85240Y309611D01*
X85221Y309624D01*
X85215Y309633D01*
X85190Y309653D01*
X85170Y309678D01*
X85160Y309684D01*
X85137Y309718D01*
X85117Y309739D01*
X85082Y309762D01*
X85077Y309772D01*
X85051Y309792D01*
X85032Y309817D01*
X85022Y309822D01*
X84999Y309857D01*
X84978Y309878D01*
X84936Y309906D01*
X84916Y309926D01*
X84893Y309956D01*
X84878Y309964D01*
X84842Y310000D01*
X84820Y310061D01*
X84778Y310130D01*
X84721Y310193D01*
X84682Y310251D01*
X84633Y310470D01*
X84614Y310513D01*
X84606Y310546D01*
X84597Y310566D01*
X84595Y310588D01*
X84574Y310664D01*
X84568Y310677D01*
X84552Y310930D01*
X84551Y310932D01*
X84563Y311079D01*
X84563Y311084D01*
X84564Y311088D01*
X84573Y311206D01*
X84591Y311245D01*
X84602Y311261D01*
X84604Y311272D01*
X84606Y311276D01*
X84611Y311285D01*
X84639Y311354D01*
X84642Y311367D01*
X84649Y311379D01*
X84662Y311412D01*
X84671Y311433D01*
X84674Y311443D01*
X84683Y311469D01*
X84687Y311488D01*
X84711Y311542D01*
X84798Y311683D01*
X84820Y311744D01*
X84865Y311813D01*
X84886Y311842D01*
X84891Y311852D01*
X84895Y311860D01*
X84906Y311885D01*
X84914Y311904D01*
X84924Y311912D01*
X84930Y311922D01*
X84964Y311945D01*
X84999Y311979D01*
X85015Y312004D01*
X85018Y312006D01*
X85037Y312031D01*
X85063Y312051D01*
X85068Y312060D01*
X85103Y312083D01*
X85124Y312104D01*
X85147Y312139D01*
X85156Y312144D01*
X85176Y312170D01*
X85182Y312175D01*
X85220Y312187D01*
X85273Y312216D01*
X85351Y312251D01*
X85392Y312281D01*
X85420Y312291D01*
X85517Y312351D01*
X85566Y312355D01*
X85663Y312383D01*
X85804Y312455D01*
X85827Y312461D01*
X85861Y312462D01*
X85972Y312490D01*
X86006Y312506D01*
X86247Y312513D01*
X86303Y312526D01*
X93663Y312540D01*
X93674Y312542D01*
X93685Y312540D01*
X94781Y312554D01*
X94821Y312563D01*
X94862Y312557D01*
X95389Y312584D01*
X95478Y312607D01*
X95570Y312602D01*
X95668Y312616D01*
X95841Y312677D01*
X96024Y312700D01*
X96086Y312721D01*
X96115Y312737D01*
X96146Y312742D01*
X96175Y312753D01*
X96231Y312757D01*
X96328Y312785D01*
X96468Y312857D01*
X96498Y312864D01*
X96533Y312881D01*
X96589Y312891D01*
X96679Y312925D01*
X96702Y312940D01*
X96904Y312982D01*
X97001Y313024D01*
X97042Y313052D01*
X97085Y313068D01*
X97109Y313074D01*
X97137Y313088D01*
X97156Y313103D01*
X97200Y313111D01*
X97470Y313292D01*
X97538Y313316D01*
X97607Y313358D01*
X97667Y313412D01*
X97792Y313487D01*
X97814Y313517D01*
X97817Y313518D01*
X97844Y313532D01*
X97933Y313600D01*
X97937Y313603D01*
X98259Y313813D01*
X98267Y313824D01*
X98277Y313831D01*
X98333Y313886D01*
X98374Y313914D01*
X99068Y314607D01*
X99081Y314628D01*
X99102Y314641D01*
X99129Y314669D01*
X99140Y314685D01*
X99194Y314727D01*
X99255Y314834D01*
X99291Y314860D01*
X99335Y314932D01*
X99417Y315010D01*
X99452Y315058D01*
X99515Y315198D01*
X99575Y315276D01*
X99615Y315356D01*
X99733Y315541D01*
X99738Y315549D01*
X99789Y315616D01*
X99803Y315644D01*
X99805Y315650D01*
X99940Y315851D01*
X99945Y315877D01*
X99959Y315900D01*
X99989Y315978D01*
X100011Y316034D01*
X100012Y316035D01*
X100059Y316110D01*
X100072Y316128D01*
X100075Y316136D01*
X100084Y316149D01*
X100097Y316183D01*
X100141Y316280D01*
X100145Y316299D01*
X100189Y316364D01*
X100192Y316377D01*
X100199Y316388D01*
X100226Y316457D01*
X100738Y316810D01*
X101271Y316930D01*
X101401Y316946D01*
X101441Y316944D01*
X101666Y316892D01*
X101977Y316624D01*
X101982Y316612D01*
X101986Y316562D01*
X102021Y316445D01*
X102110Y316275D01*
X102114Y316246D01*
X102177Y316073D01*
X102202Y316031D01*
X102211Y315983D01*
X102382Y315728D01*
X102382Y315727D01*
X102396Y315699D01*
X102421Y315667D01*
X102551Y315451D01*
X102565Y315424D01*
X102572Y315415D01*
X102577Y315407D01*
X102604Y315340D01*
X102611Y315330D01*
X102613Y315317D01*
X102641Y315276D01*
X102735Y315128D01*
X102751Y315112D01*
X102769Y315084D01*
X102816Y314985D01*
X102818Y314979D01*
X102821Y314974D01*
X102831Y314953D01*
X102837Y314948D01*
X102860Y314910D01*
X102946Y314815D01*
X103038Y314673D01*
X103048Y314666D01*
X103055Y314656D01*
X103075Y314636D01*
X103102Y314588D01*
X103136Y314562D01*
X103166Y314517D01*
X103201Y314482D01*
X103226Y314466D01*
X103227Y314464D01*
X103257Y314441D01*
X103277Y314420D01*
X103305Y314379D01*
X103326Y314358D01*
X103360Y314335D01*
X103366Y314325D01*
X103391Y314305D01*
X103411Y314280D01*
X103413Y314279D01*
X103430Y314254D01*
X103464Y314219D01*
X103506Y314191D01*
X103513Y314185D01*
X103536Y314155D01*
X103545Y314149D01*
X103568Y314115D01*
X103589Y314094D01*
X103640Y314060D01*
X103674Y314016D01*
X103722Y313989D01*
X103749Y313962D01*
X103771Y313948D01*
X103786Y313926D01*
X103928Y313836D01*
X103982Y313788D01*
X104051Y313746D01*
X104054Y313745D01*
X104067Y313731D01*
X104162Y313686D01*
X104172Y313680D01*
X104201Y313642D01*
X104230Y313626D01*
X104251Y313613D01*
X104285Y313573D01*
X104348Y313524D01*
X104589Y313403D01*
X104664Y313350D01*
X104745Y313313D01*
X104903Y313218D01*
X104977Y313190D01*
X105046Y313146D01*
X105075Y313125D01*
X105085Y313120D01*
X105092Y313116D01*
X105118Y313106D01*
X105141Y313095D01*
X105157Y313086D01*
X105159Y313085D01*
X105160Y313084D01*
X105178Y313078D01*
X105227Y313056D01*
X105289Y313041D01*
X105540Y312958D01*
X105674Y312913D01*
X105764Y312857D01*
X105875Y312816D01*
X106039Y312789D01*
X106053Y312783D01*
X106064Y312777D01*
X106081Y312766D01*
X106095Y312761D01*
X106120Y312748D01*
X106159Y312736D01*
X106171Y312731D01*
X106180Y312730D01*
X106191Y312725D01*
X106207Y312722D01*
X106234Y312714D01*
X106258Y312700D01*
X106300Y312686D01*
X106588Y312650D01*
X106869Y312583D01*
X107244Y312569D01*
X107262Y312572D01*
X107352Y312554D01*
X110403Y312540D01*
X110407Y312541D01*
X110412Y312540D01*
X111632D01*
X111645Y312543D01*
X111658Y312540D01*
X112754Y312554D01*
X112794Y312563D01*
X112835Y312557D01*
X113362Y312584D01*
X113451Y312607D01*
X113543Y312602D01*
X113640Y312616D01*
X113814Y312677D01*
X113997Y312700D01*
X114059Y312721D01*
X114093Y312740D01*
X114130Y312746D01*
X114241Y312788D01*
X114281Y312813D01*
X114530Y312875D01*
X114771Y312989D01*
X114874Y313035D01*
X114948Y313088D01*
X115036Y313116D01*
X115089Y313145D01*
X115167Y313181D01*
X115212Y313214D01*
X115221Y313217D01*
X115273Y313250D01*
X115333Y313264D01*
X115409Y313298D01*
X115468Y313341D01*
X115471Y313342D01*
X115482Y313349D01*
X115496Y313352D01*
X115565Y313379D01*
X115576Y313386D01*
X115588Y313389D01*
X115685Y313454D01*
X115696Y313458D01*
X115780Y313514D01*
X115782Y313516D01*
X115790Y313518D01*
X115818Y313532D01*
X115868Y313571D01*
X115872Y313574D01*
X115917Y313608D01*
X116232Y313813D01*
X116239Y313824D01*
X116250Y313831D01*
X116305Y313886D01*
X116347Y313914D01*
X116375Y313942D01*
X116389Y313962D01*
X116409Y313976D01*
X116472Y314038D01*
X116501Y314061D01*
X116510Y314077D01*
X117027Y314594D01*
X117057Y314639D01*
X117153Y314713D01*
X117180Y314761D01*
X117181Y314762D01*
X117222Y314797D01*
X117256Y314841D01*
X117262Y314845D01*
X117445Y315148D01*
X117450Y315154D01*
X117485Y315200D01*
X117499Y315227D01*
X117499Y315228D01*
X117577Y315345D01*
X117653Y315433D01*
X117709Y315530D01*
X117719Y315562D01*
X117797Y315648D01*
X117825Y315727D01*
X117899Y315837D01*
X117901Y315850D01*
X117908Y315861D01*
X117936Y315930D01*
X117967Y316099D01*
X117979Y316127D01*
X117981Y316134D01*
X118023Y316198D01*
X118026Y316210D01*
X118033Y316221D01*
X118060Y316290D01*
X118063Y316304D01*
X118071Y316316D01*
X118100Y316394D01*
X118123Y316450D01*
X118137Y316524D01*
X118141Y316535D01*
X118277Y316824D01*
X118305Y316934D01*
X118307Y316973D01*
X118310Y316981D01*
X118309Y317018D01*
X118309Y317019D01*
X118319Y317066D01*
X118330Y317099D01*
X118402Y317272D01*
X118430Y317411D01*
X118430Y317468D01*
X118449Y317522D01*
X118470Y317668D01*
X118466Y317750D01*
X118487Y317829D01*
X118493Y317931D01*
X118498Y317945D01*
X118507Y318012D01*
X118603Y318313D01*
X118617Y318438D01*
X118614Y318469D01*
X118614Y318469D01*
X118614Y318471D01*
X118602Y318610D01*
X118615Y318667D01*
X118583Y318848D01*
X118568Y319158D01*
X118554Y319213D01*
X118549Y319225D01*
X118549Y319231D01*
X118521Y319284D01*
X118501Y319327D01*
X118496Y319354D01*
X118491Y319401D01*
X118480Y319594D01*
X118453Y319700D01*
X118456Y319810D01*
X118448Y319857D01*
X118432Y319981D01*
X118350Y320224D01*
X118345Y320255D01*
X118323Y320318D01*
X118309Y320379D01*
X118305Y320462D01*
X118277Y320573D01*
X118193Y320750D01*
X118168Y320853D01*
X118166Y320891D01*
X118139Y321002D01*
X118074Y321139D01*
X118044Y321288D01*
X117905Y321496D01*
X117799Y321722D01*
X117766Y321752D01*
X117709Y321832D01*
X117653Y321884D01*
X117639Y321915D01*
X117617Y321947D01*
X117610Y321961D01*
X117557Y322028D01*
X117509Y322107D01*
X117440Y322236D01*
X117399Y322286D01*
X117395Y322294D01*
X117391Y322296D01*
X117378Y322312D01*
X117361Y322326D01*
X117332Y322370D01*
X117329Y322375D01*
X117326Y322379D01*
X117320Y322387D01*
X117283Y322449D01*
X117254Y322519D01*
X117198Y322602D01*
X117176Y322624D01*
X117137Y322689D01*
X117100Y322716D01*
X117075Y322754D01*
X117069Y322760D01*
X117042Y322808D01*
X116958Y322873D01*
X116952Y322884D01*
X116937Y322896D01*
X116916Y322927D01*
X116888Y322955D01*
X116867Y322969D01*
X116853Y322990D01*
X116826Y323018D01*
X116805Y323031D01*
X116791Y323052D01*
X116729Y323114D01*
X116706Y323144D01*
X116690Y323153D01*
X116624Y323219D01*
X116604Y323233D01*
X116590Y323253D01*
X116562Y323281D01*
X116517Y323311D01*
X116442Y323407D01*
X116395Y323434D01*
X116389Y323441D01*
X116344Y323470D01*
X116343Y323472D01*
X116341Y323473D01*
X116291Y323526D01*
X116243Y323561D01*
X116137Y323609D01*
X116117Y323622D01*
X115859Y323823D01*
X115831Y323836D01*
X115803Y323844D01*
X115747Y323870D01*
X115608Y323997D01*
X115538Y324038D01*
X115436Y324075D01*
X115431Y324080D01*
X115382Y324111D01*
X115333Y324146D01*
X115180Y324216D01*
X115121Y324229D01*
X114993Y324311D01*
X114951Y324327D01*
X114874Y324361D01*
X114863Y324364D01*
X114805Y324403D01*
X114779Y324408D01*
X114756Y324422D01*
X114666Y324457D01*
X114543Y324478D01*
X114429Y324532D01*
X114374Y324546D01*
X114372Y324546D01*
X114324Y324565D01*
X114187Y324590D01*
X114061Y324650D01*
X114006Y324663D01*
X113861Y324670D01*
X113721Y324713D01*
X113538Y324732D01*
X113243Y324810D01*
X113021Y324824D01*
X112990Y324820D01*
X112890Y324842D01*
X112127Y324856D01*
X112122Y324855D01*
X112045Y324870D01*
X108072Y324863D01*
X108049Y324858D01*
X108026Y324862D01*
X107457Y324848D01*
X107422Y324841D01*
X107387Y324846D01*
X107151Y324832D01*
X107139Y324828D01*
X107126Y324830D01*
X106931Y324816D01*
X106806Y324782D01*
X106677Y324782D01*
X106607Y324768D01*
X106506Y324726D01*
X106466Y324724D01*
X106411Y324711D01*
X106310Y324697D01*
X106210Y324662D01*
X106104Y324657D01*
X106049Y324643D01*
X105819Y324534D01*
X105801Y324529D01*
X105695Y324509D01*
X105652Y324492D01*
X105547Y324453D01*
X105381Y324352D01*
X105369Y324350D01*
X105300Y324322D01*
X105279Y324308D01*
X105254Y324303D01*
X105157Y324261D01*
X105107Y324227D01*
X105048Y324211D01*
X105021Y324197D01*
X104977Y324163D01*
X104815Y324063D01*
X104765Y324049D01*
X104695Y324035D01*
X104598Y323970D01*
X104586Y323965D01*
X104575Y323958D01*
X104535Y323947D01*
X104508Y323933D01*
X104400Y323850D01*
X104226Y323763D01*
X104171Y323700D01*
X104083Y323650D01*
X104046Y323601D01*
X104033Y323593D01*
X104005Y323565D01*
X104003Y323561D01*
X103952Y323532D01*
X103929Y323503D01*
X103923Y323497D01*
X103881Y323469D01*
X103846Y323434D01*
X103823Y323399D01*
X103813Y323394D01*
X103799Y323376D01*
X103782Y323362D01*
X103781Y323360D01*
X103756Y323343D01*
X103707Y323295D01*
X103691Y323270D01*
X103688Y323269D01*
X103675Y323251D01*
X103657Y323238D01*
X103651Y323228D01*
X103617Y323204D01*
X103582Y323170D01*
X103559Y323135D01*
X103549Y323130D01*
X103536Y323112D01*
X103518Y323099D01*
X103517Y323097D01*
X103492Y323080D01*
X103444Y323031D01*
X103418Y322993D01*
X103394Y322974D01*
X103385Y322959D01*
X103381Y322955D01*
X103376Y322948D01*
X103365Y322939D01*
X103325Y322890D01*
X103255Y322835D01*
X103242Y322813D01*
X103227Y322800D01*
X103222Y322795D01*
X103217Y322791D01*
X103156Y322716D01*
X103121Y322687D01*
X103120Y322686D01*
X103119Y322685D01*
X103079Y322652D01*
X103017Y322577D01*
X102940Y322513D01*
X102881Y322441D01*
X102853Y322419D01*
X102741Y322223D01*
X102598Y322050D01*
X102549Y321960D01*
X102529Y321893D01*
X102488Y321837D01*
X102458Y321770D01*
X102449Y321755D01*
X102444Y321740D01*
X102419Y321684D01*
X102410Y321648D01*
X102408Y321645D01*
X102303Y321546D01*
X102242Y321410D01*
X102174Y321323D01*
X102160Y321295D01*
X102146Y321242D01*
X102079Y321143D01*
X102046Y320976D01*
X101976Y320821D01*
X101443Y320493D01*
X101078Y320330D01*
X100893Y320293D01*
X100540Y320295D01*
X100415Y320351D01*
X100357Y320474D01*
X100354Y320493D01*
X100323Y320576D01*
X100312Y320648D01*
X100295Y320692D01*
X100293Y320700D01*
X100287Y320713D01*
X100270Y320759D01*
X100256Y320782D01*
X100214Y320978D01*
X100173Y321075D01*
X100134Y321131D01*
X100108Y321196D01*
X100095Y321217D01*
X100090Y321242D01*
X100048Y321339D01*
X99996Y321415D01*
X99969Y321502D01*
X99872Y321683D01*
X99850Y321709D01*
X99845Y321737D01*
X99817Y321806D01*
X99810Y321817D01*
X99808Y321829D01*
X99780Y321870D01*
X99686Y322019D01*
X99670Y322035D01*
X99665Y322043D01*
X99665Y322044D01*
X99651Y322071D01*
X99643Y322082D01*
X99590Y322193D01*
X99529Y322248D01*
X99383Y322473D01*
X99373Y322480D01*
X99366Y322491D01*
X99297Y322560D01*
X99269Y322602D01*
X98652Y323219D01*
X98631Y323232D01*
X98618Y323253D01*
X98590Y323280D01*
X98545Y323311D01*
X98470Y323407D01*
X98422Y323434D01*
X98416Y323441D01*
X98372Y323470D01*
X98370Y323472D01*
X98368Y323473D01*
X98319Y323526D01*
X98270Y323561D01*
X98164Y323609D01*
X98144Y323622D01*
X97886Y323823D01*
X97858Y323836D01*
X97830Y323844D01*
X97775Y323870D01*
X97635Y323997D01*
X97565Y324038D01*
X97463Y324075D01*
X97459Y324080D01*
X97410Y324111D01*
X97360Y324146D01*
X97208Y324216D01*
X97149Y324229D01*
X97020Y324311D01*
X96965Y324332D01*
X96904Y324358D01*
X96896Y324360D01*
X96832Y324403D01*
X96806Y324408D01*
X96784Y324422D01*
X96694Y324457D01*
X96570Y324478D01*
X96456Y324532D01*
X96401Y324546D01*
X96348Y324548D01*
X96276Y324564D01*
X96108Y324641D01*
X95962Y324676D01*
X95868Y324679D01*
X95779Y324711D01*
X95718Y324719D01*
X95705Y324724D01*
X95642Y324732D01*
X95571Y324761D01*
X95502Y324775D01*
X95354Y324775D01*
X95136Y324827D01*
X94761Y324841D01*
X94739Y324837D01*
X94644Y324856D01*
X18857Y324870D01*
X18590Y324817D01*
X18320Y324798D01*
X18243Y324777D01*
X18146Y324729D01*
X18076Y324715D01*
X17952Y324632D01*
X17907Y324609D01*
X17566Y324448D01*
X17460Y324376D01*
X17238Y324234D01*
X16624Y324050D01*
X16102Y324092D01*
X16033Y324109D01*
X15785Y324192D01*
X15734Y324216D01*
X15705Y324222D01*
X15622Y324278D01*
X15596Y324283D01*
X15574Y324297D01*
X15496Y324327D01*
X15439Y324350D01*
X15430Y324351D01*
X15364Y324393D01*
X15359Y324397D01*
X15350Y324402D01*
X15296Y324436D01*
X15258Y324450D01*
X15241Y324459D01*
X15213Y324468D01*
X15162Y324488D01*
X15116Y324497D01*
X14994Y324534D01*
X14759Y324641D01*
X14613Y324676D01*
X14519Y324679D01*
X14430Y324711D01*
X14393Y324716D01*
X14370Y324724D01*
X14344Y324727D01*
X14317Y324740D01*
X14261Y324753D01*
X14069Y324763D01*
X13798Y324827D01*
X13410Y324841D01*
X13390Y324838D01*
X13299Y324856D01*
X6601Y324870D01*
X6521Y324854D01*
X6441Y324864D01*
X6338Y324856D01*
X6262Y324867D01*
X6058Y324855D01*
X5977Y324867D01*
X5845Y324860D01*
X5788Y324846D01*
X5786Y324846D01*
X5404Y324825D01*
X5348Y324811D01*
X4446Y325244D01*
X4218Y325490D01*
X4210Y325502D01*
X4078Y325734D01*
Y487769D01*
X5348Y488022D01*
X6354Y485593D01*
X8278Y483086D01*
X10785Y481162D01*
X13704Y479953D01*
X16836Y479541D01*
X19969Y479953D01*
X22888Y481162D01*
X25395Y483086D01*
X27318Y485593D01*
X28528Y488512D01*
X28940Y491645D01*
X28528Y494777D01*
X27318Y497696D01*
X25395Y500203D01*
X22888Y502127D01*
X21621Y502651D01*
X21874Y503921D01*
X485734Y503922D01*
X486165Y502652D01*
D02*
G37*
G36*
X13295Y322817D02*
X13337Y322803D01*
X13725Y322789D01*
X13767Y322775D01*
X13822Y322761D01*
X13892Y322734D01*
X13947Y322720D01*
X14141Y322692D01*
X14287Y322657D01*
X14405Y322595D01*
X14474Y322567D01*
X14564Y322533D01*
X14613Y322498D01*
X14682Y322456D01*
X14751Y322429D01*
X14842Y322394D01*
X14862Y322373D01*
X14890Y322359D01*
X15043Y322290D01*
X15140Y322234D01*
X15209Y322193D01*
X15278Y322165D01*
X15334Y322151D01*
X15410Y322089D01*
X15459Y322040D01*
X15486Y322026D01*
X15549Y321964D01*
X15563Y321936D01*
X15583Y321915D01*
X15611Y321902D01*
X15688Y321825D01*
X15701Y321797D01*
X15722Y321777D01*
X15750Y321763D01*
X15826Y321687D01*
X15840Y321659D01*
X15861Y321638D01*
X15889Y321624D01*
X15951Y321562D01*
X15965Y321534D01*
X15999Y321499D01*
X16027Y321485D01*
X16076Y321437D01*
X16090Y321409D01*
X16173Y321326D01*
X16201Y321257D01*
X16235Y321166D01*
X16270Y321118D01*
X16339Y321049D01*
X16381Y320979D01*
X16450Y320910D01*
X16499Y320778D01*
X16520Y320730D01*
X16589Y320619D01*
X16603Y320522D01*
X16617Y320466D01*
X16631Y320383D01*
X16728Y320175D01*
X16748Y320043D01*
X16804Y319904D01*
X16818Y319849D01*
X16832Y319766D01*
X16846Y319461D01*
X16859Y319086D01*
X16873Y318254D01*
X16880Y284798D01*
Y284784D01*
X16873Y255585D01*
X16880Y255537D01*
X16866Y255495D01*
X16873Y255266D01*
X16866Y255051D01*
X16880Y255010D01*
X16866Y254954D01*
X16852Y254857D01*
X16866Y254802D01*
X16873Y254726D01*
X16859Y254656D01*
X16846Y254601D01*
X16832Y254240D01*
X16804Y254171D01*
X16707Y254074D01*
X16637Y254046D01*
X16249Y254032D01*
X16207Y254018D01*
X16152Y254004D01*
X16020Y254025D01*
X15986Y254032D01*
X15944Y254018D01*
X15847Y254004D01*
X15708Y254018D01*
X15570Y254004D01*
X15285Y254011D01*
X15181Y254004D01*
X15140Y254018D01*
X15063Y254025D01*
X14980Y254011D01*
X14904Y254004D01*
X14862Y254018D01*
X14751Y254046D01*
X14405Y254060D01*
X14328Y254122D01*
X14273Y254178D01*
X14245Y254247D01*
X14231Y254635D01*
X14217Y254677D01*
X14204Y254774D01*
X14217Y254816D01*
X14231Y254899D01*
X14217Y254940D01*
X14204Y255038D01*
X14217Y255093D01*
X14211Y255336D01*
X14217Y255495D01*
X14204Y255537D01*
X14211Y255724D01*
X14197Y318337D01*
X14190Y318386D01*
X14204Y318428D01*
X14190Y318663D01*
X14176Y318705D01*
X14162Y319149D01*
X14134Y319218D01*
X14093Y319315D01*
X14079Y319371D01*
X14023Y319468D01*
X13968Y319523D01*
X13954Y319551D01*
X13892Y319627D01*
X13864Y319641D01*
X13801Y319704D01*
X13788Y319731D01*
X13753Y319766D01*
X13725Y319780D01*
X13649Y319842D01*
X13614Y319877D01*
X13545Y319904D01*
X13469Y319925D01*
X13295Y320015D01*
X13240Y320029D01*
X13129Y320043D01*
X13087Y320057D01*
X12990Y320099D01*
X12935Y320112D01*
X12754Y320126D01*
X12429Y320147D01*
X11860Y320161D01*
X6479Y320175D01*
X6389Y320182D01*
X6348Y320168D01*
X6098Y320182D01*
X6056Y320168D01*
X5890Y320182D01*
X5848Y320196D01*
X5515Y320210D01*
X5446Y320251D01*
X5370Y320314D01*
X5356Y320341D01*
X5328Y320411D01*
X5321Y320639D01*
X5328Y320716D01*
X5314Y320757D01*
X5293Y320848D01*
X5287Y320952D01*
X5300Y320993D01*
X5293Y321250D01*
X5300Y321368D01*
X5287Y321409D01*
X5293Y321749D01*
X5287Y321867D01*
X5300Y321908D01*
X5293Y322151D01*
X5307Y322207D01*
X5321Y322276D01*
X5328Y322352D01*
X5314Y322380D01*
X5328Y322422D01*
X5342Y322643D01*
X5391Y322706D01*
X5418Y322720D01*
X5446Y322761D01*
X5515Y322789D01*
X5897Y322810D01*
X5952Y322824D01*
X6084Y322831D01*
X6126Y322817D01*
X6375Y322831D01*
X6417Y322817D01*
X6597Y322831D01*
X13295Y322817D01*
D02*
G37*
G36*
X112090D02*
X112853Y322803D01*
X112894Y322789D01*
X113116Y322775D01*
X113213Y322734D01*
X113310Y322706D01*
X113511Y322685D01*
X113567Y322671D01*
X113636Y322643D01*
X113782Y322581D01*
X113879Y322567D01*
X113934Y322553D01*
X114024Y322519D01*
X114045Y322498D01*
X114170Y322442D01*
X114260Y322408D01*
X114337Y322359D01*
X114489Y322290D01*
X114558Y322248D01*
X114614Y322193D01*
X114642Y322179D01*
X114746Y322103D01*
X114753Y322082D01*
X114780Y322068D01*
X114919Y322012D01*
X114947Y321999D01*
X115030Y321915D01*
X115058Y321902D01*
X115106Y321867D01*
X115120Y321839D01*
X115148Y321811D01*
X115155Y321791D01*
X115183Y321777D01*
X115349Y321610D01*
X115370Y321603D01*
X115384Y321576D01*
X115411Y321548D01*
X115418Y321527D01*
X115446Y321513D01*
X115474Y321485D01*
X115501Y321472D01*
X115557Y321388D01*
X115633Y321312D01*
X115689Y321160D01*
X115751Y321083D01*
X115786Y321049D01*
X115800Y321021D01*
X115862Y320945D01*
X115897Y320910D01*
X115945Y320778D01*
X115980Y320730D01*
X116035Y320674D01*
X116049Y320647D01*
X116119Y320549D01*
X116160Y320508D01*
X116188Y320397D01*
X116202Y320286D01*
X116299Y320078D01*
X116327Y319967D01*
X116340Y319870D01*
X116410Y319717D01*
X116431Y319558D01*
X116444Y319475D01*
X116458Y319239D01*
X116472Y319100D01*
X116486Y318975D01*
X116500Y318920D01*
X116542Y318809D01*
X116576Y318719D01*
X116590Y318663D01*
X116576Y318539D01*
X116507Y318386D01*
X116493Y318330D01*
X116479Y318234D01*
X116465Y318178D01*
X116451Y317956D01*
X116431Y317810D01*
X116403Y317672D01*
X116340Y317526D01*
X116327Y317429D01*
X116299Y317318D01*
X116229Y317207D01*
X116202Y317138D01*
X116167Y317048D01*
X116139Y316978D01*
X116119Y316958D01*
X116105Y316930D01*
X116063Y316833D01*
X116042Y316687D01*
X116015Y316618D01*
X115938Y316542D01*
X115883Y316444D01*
X115814Y316375D01*
X115758Y316223D01*
X115675Y316139D01*
X115661Y316112D01*
X115612Y316049D01*
X115585Y316035D01*
X114967Y315418D01*
X114961Y315397D01*
X114933Y315384D01*
X114905Y315356D01*
X114877Y315342D01*
X114808Y315273D01*
X114739Y315245D01*
X114649Y315210D01*
X114565Y315155D01*
X114489Y315120D01*
X114399Y315086D01*
X114323Y315037D01*
X114170Y314968D01*
X114045Y314898D01*
X113920Y314843D01*
X113657Y314718D01*
X113525Y314697D01*
X113414Y314656D01*
X113352Y314635D01*
X113255Y314621D01*
X112728Y314593D01*
X111632Y314579D01*
X110412D01*
X107361Y314593D01*
X107319Y314607D01*
X106945Y314621D01*
X106903Y314635D01*
X106813Y314669D01*
X106695Y314704D01*
X106591Y314725D01*
X106480Y314767D01*
X106390Y314815D01*
X106279Y314843D01*
X106168Y314857D01*
X106071Y314912D01*
X105919Y314981D01*
X105849Y315009D01*
X105752Y315079D01*
X105600Y315134D01*
X105537Y315182D01*
X105524Y315210D01*
X105406Y315287D01*
X105336Y315356D01*
X105281Y315370D01*
X105191Y315404D01*
X105100Y315494D01*
X105031Y315536D01*
X105010Y315557D01*
X104997Y315585D01*
X104934Y315647D01*
X104906Y315661D01*
X104872Y315696D01*
X104858Y315723D01*
X104795Y315786D01*
X104768Y315800D01*
X104747Y315821D01*
X104733Y315848D01*
X104671Y315911D01*
X104643Y315924D01*
X104608Y315959D01*
X104567Y316028D01*
X104497Y316098D01*
X104469Y316167D01*
X104456Y316223D01*
X104359Y316375D01*
X104345Y316431D01*
X104275Y316556D01*
X104220Y316611D01*
X104206Y316639D01*
X104144Y316715D01*
X104095Y316763D01*
X104033Y316937D01*
X103977Y317020D01*
X103943Y317138D01*
X103922Y317256D01*
X103894Y317325D01*
X103859Y317401D01*
X103832Y317471D01*
X103818Y317526D01*
X103804Y317665D01*
X103790Y317776D01*
X103735Y317915D01*
X103721Y317970D01*
X103700Y318199D01*
X103686Y318421D01*
X103679Y318982D01*
X103693Y319024D01*
X103707Y319357D01*
X103721Y319398D01*
X103735Y319495D01*
X103762Y319565D01*
X103790Y319662D01*
X103839Y319960D01*
X103866Y320029D01*
X103929Y320175D01*
X103943Y320272D01*
X103963Y320362D01*
X103984Y320383D01*
X103998Y320411D01*
X104053Y320466D01*
X104067Y320494D01*
X104130Y320570D01*
X104151Y320591D01*
X104164Y320619D01*
X104220Y320743D01*
X104275Y320841D01*
X104345Y320993D01*
X104393Y321083D01*
X104421Y321097D01*
X104442Y321118D01*
X104456Y321146D01*
X104518Y321222D01*
X104594Y321284D01*
X104657Y321361D01*
X104733Y321423D01*
X104795Y321499D01*
X104823Y321513D01*
X104872Y321562D01*
X104886Y321590D01*
X104934Y321638D01*
X104962Y321652D01*
X105010Y321700D01*
X105024Y321728D01*
X105059Y321763D01*
X105087Y321777D01*
X105135Y321825D01*
X105149Y321853D01*
X105198Y321902D01*
X105225Y321915D01*
X105274Y321964D01*
X105288Y321992D01*
X105322Y322026D01*
X105350Y322040D01*
X105378Y322068D01*
X105406Y322082D01*
X105420Y322109D01*
X105447Y322123D01*
X105475Y322151D01*
X105551Y322172D01*
X105634Y322214D01*
X105718Y322269D01*
X105829Y322311D01*
X105898Y322338D01*
X105933Y322373D01*
X105960Y322387D01*
X106057Y322429D01*
X106127Y322456D01*
X106154Y322470D01*
X106252Y322539D01*
X106383Y322588D01*
X106453Y322616D01*
X106543Y322664D01*
X106598Y322678D01*
X106792Y322706D01*
X106938Y322741D01*
X107007Y322768D01*
X107077Y322782D01*
X107271Y322796D01*
X107507Y322810D01*
X108075Y322824D01*
X112048Y322831D01*
X112090Y322817D01*
D02*
G37*
G36*
X94644D02*
X94686Y322803D01*
X95060Y322789D01*
X95102Y322775D01*
X95171Y322761D01*
X95240Y322734D01*
X95296Y322720D01*
X95490Y322692D01*
X95636Y322657D01*
X95809Y322581D01*
X95906Y322567D01*
X95962Y322553D01*
X96052Y322519D01*
X96073Y322498D01*
X96100Y322484D01*
X96197Y322442D01*
X96287Y322408D01*
X96364Y322359D01*
X96516Y322290D01*
X96586Y322248D01*
X96641Y322193D01*
X96669Y322179D01*
X96773Y322103D01*
X96780Y322082D01*
X96808Y322068D01*
X96946Y322012D01*
X96974Y321999D01*
X97057Y321915D01*
X97085Y321902D01*
X97134Y321867D01*
X97147Y321839D01*
X97175Y321811D01*
X97182Y321791D01*
X97210Y321777D01*
X97827Y321160D01*
X97841Y321132D01*
X97924Y321049D01*
X97952Y320979D01*
X97965Y320924D01*
X98063Y320771D01*
X98076Y320716D01*
X98174Y320536D01*
X98215Y320438D01*
X98243Y320369D01*
X98298Y320272D01*
X98340Y320175D01*
X98361Y320043D01*
X98402Y319932D01*
X98437Y319856D01*
X98451Y319800D01*
X98465Y319704D01*
X98479Y319648D01*
X98499Y319405D01*
X98513Y319350D01*
X98576Y319149D01*
X98596Y318975D01*
X98610Y318726D01*
X98617Y318691D01*
X98603Y318650D01*
X98590Y318330D01*
X98576Y318289D01*
X98562Y318192D01*
X98534Y318123D01*
X98506Y318025D01*
X98492Y317970D01*
X98472Y317727D01*
X98458Y317644D01*
X98444Y317575D01*
X98416Y317505D01*
X98382Y317429D01*
X98354Y317332D01*
X98333Y317214D01*
X98305Y317145D01*
X98285Y317124D01*
X98215Y316971D01*
X98181Y316881D01*
X98132Y316819D01*
X98118Y316791D01*
X98090Y316722D01*
X98056Y316632D01*
X97979Y316556D01*
X97965Y316528D01*
X97868Y316403D01*
X97841Y316375D01*
X97792Y316243D01*
X97758Y316195D01*
X97702Y316139D01*
X97688Y316112D01*
X97660Y316084D01*
X97654Y316063D01*
X97626Y316049D01*
X96932Y315356D01*
X96905Y315342D01*
X96835Y315273D01*
X96766Y315245D01*
X96676Y315210D01*
X96613Y315148D01*
X96586Y315134D01*
X96558Y315106D01*
X96489Y315065D01*
X96419Y314995D01*
X96246Y314933D01*
X96225Y314912D01*
X96197Y314898D01*
X96100Y314857D01*
X96003Y314843D01*
X95948Y314829D01*
X95858Y314794D01*
X95767Y314746D01*
X95670Y314718D01*
X95573Y314704D01*
X95442Y314656D01*
X95379Y314635D01*
X95282Y314621D01*
X94755Y314593D01*
X93660Y314579D01*
X86226Y314565D01*
X86185Y314552D01*
X85727Y314538D01*
X85686Y314524D01*
X85575Y314510D01*
X85478Y314468D01*
X85367Y314441D01*
X85283Y314427D01*
X85103Y314343D01*
X85006Y314316D01*
X84909Y314302D01*
X84819Y314267D01*
X84715Y314205D01*
X84583Y314156D01*
X84507Y314108D01*
X84354Y314038D01*
X84229Y313969D01*
X84105Y313914D01*
X84008Y313858D01*
X83980Y313830D01*
X83952Y313817D01*
X83910Y313775D01*
X83883Y313761D01*
X83834Y313713D01*
X83820Y313685D01*
X83786Y313650D01*
X83758Y313636D01*
X83695Y313574D01*
X83682Y313546D01*
X83661Y313525D01*
X83633Y313511D01*
X83571Y313449D01*
X83557Y313421D01*
X83522Y313387D01*
X83494Y313373D01*
X83432Y313310D01*
X83418Y313283D01*
X83384Y313248D01*
X83356Y313234D01*
X83307Y313186D01*
X83293Y313158D01*
X83252Y313116D01*
X83238Y313088D01*
X83196Y313047D01*
X83148Y312915D01*
X83099Y312839D01*
X83030Y312686D01*
X83002Y312617D01*
X82933Y312520D01*
X82884Y312388D01*
X82815Y312277D01*
X82780Y312201D01*
X82746Y312111D01*
X82718Y312041D01*
X82697Y312021D01*
X82683Y311993D01*
X82655Y311924D01*
X82641Y311826D01*
X82628Y311771D01*
X82593Y311681D01*
X82558Y311563D01*
X82544Y311424D01*
X82531Y311244D01*
X82510Y310987D01*
X82503Y310842D01*
X82517Y310800D01*
X82537Y310474D01*
X82551Y310322D01*
X82565Y310239D01*
X82607Y310128D01*
X82628Y310051D01*
X82641Y309996D01*
X82662Y309892D01*
X82690Y309823D01*
X82766Y309649D01*
X82794Y309483D01*
X82850Y309386D01*
X82891Y309289D01*
X82919Y309219D01*
X82961Y309150D01*
X83030Y309081D01*
X83071Y309011D01*
X83141Y308942D01*
X83168Y308873D01*
X83203Y308783D01*
X83238Y308734D01*
X83293Y308678D01*
X83307Y308651D01*
X83508Y308450D01*
X83536Y308436D01*
X83557Y308415D01*
X83571Y308387D01*
X83647Y308311D01*
X83675Y308297D01*
X83695Y308276D01*
X83709Y308249D01*
X83786Y308172D01*
X83813Y308158D01*
X83834Y308138D01*
X83848Y308110D01*
X83910Y308048D01*
X83938Y308034D01*
X84008Y307964D01*
X84035Y307950D01*
X84105Y307923D01*
X84160Y307909D01*
X84236Y307846D01*
X84285Y307798D01*
X84313Y307784D01*
X84389Y307722D01*
X84424Y307687D01*
X84493Y307659D01*
X84625Y307611D01*
X84645Y307590D01*
X84673Y307576D01*
X84770Y307534D01*
X84867Y307521D01*
X84944Y307500D01*
X85013Y307472D01*
X85186Y307396D01*
X85318Y307375D01*
X85519Y307313D01*
X85658Y307299D01*
X86039Y307278D01*
X86594Y307264D01*
X132150Y307250D01*
X132691Y307236D01*
X132940Y307222D01*
X133211Y307202D01*
X133280Y307174D01*
X133377Y307146D01*
X133474Y307132D01*
X133689Y307111D01*
X133772Y307098D01*
X133828Y307084D01*
X133897Y307056D01*
X133973Y307021D01*
X134084Y306994D01*
X134188Y306973D01*
X134258Y306945D01*
X134278Y306924D01*
X134431Y306855D01*
X134521Y306820D01*
X134542Y306799D01*
X134570Y306786D01*
X134722Y306716D01*
X134847Y306647D01*
X134875Y306619D01*
X134951Y306598D01*
X135021Y306571D01*
X135069Y306536D01*
X135125Y306480D01*
X135152Y306467D01*
X135180Y306439D01*
X135208Y306425D01*
X135242Y306376D01*
X135305Y306314D01*
X135332Y306300D01*
X135402Y306231D01*
X135429Y306217D01*
X135499Y306189D01*
X135554Y306175D01*
X135631Y306113D01*
X135679Y306064D01*
X135707Y306050D01*
X135769Y305988D01*
X135783Y305960D01*
X135818Y305912D01*
X135846Y305898D01*
X135880Y305836D01*
X135929Y305704D01*
X136005Y305628D01*
X136019Y305600D01*
X136109Y305510D01*
X136137Y305496D01*
X136192Y305413D01*
X136269Y305336D01*
X136331Y305163D01*
X136366Y305128D01*
X136379Y305101D01*
X136435Y304976D01*
X136463Y304907D01*
X136532Y304809D01*
X136546Y304754D01*
X136574Y304685D01*
X136671Y304477D01*
X136699Y304282D01*
X136719Y304165D01*
X136768Y304005D01*
X136782Y303908D01*
X136803Y303651D01*
X136816Y303291D01*
X136823Y302868D01*
X136809Y302826D01*
X136796Y302355D01*
X136782Y302313D01*
X136768Y302091D01*
X136740Y302022D01*
X136712Y301925D01*
X136685Y301731D01*
X136664Y301627D01*
X136636Y301557D01*
X136615Y301537D01*
X136560Y301398D01*
X136525Y301308D01*
X136504Y301287D01*
X136490Y301259D01*
X136463Y301231D01*
X136393Y301051D01*
X136310Y300968D01*
X136296Y300940D01*
X136234Y300864D01*
X136213Y300843D01*
X136199Y300815D01*
X136158Y300718D01*
X136102Y300621D01*
X136033Y300552D01*
X136019Y300524D01*
X135804Y300309D01*
X135783Y300302D01*
X135769Y300275D01*
X135679Y300184D01*
X135658Y300177D01*
X135645Y300150D01*
X135416Y299921D01*
X135388Y299907D01*
X135353Y299858D01*
X135291Y299796D01*
X135263Y299782D01*
X135180Y299699D01*
X135111Y299671D01*
X135021Y299637D01*
X134937Y299581D01*
X134861Y299547D01*
X134771Y299512D01*
X134694Y299463D01*
X134570Y299408D01*
X134417Y299325D01*
X134265Y299255D01*
X134057Y299158D01*
X133862Y299130D01*
X133745Y299110D01*
X133585Y299061D01*
X133530Y299047D01*
X133162Y299027D01*
X132594Y299013D01*
X103596Y298999D01*
X103589Y298992D01*
X103547Y299006D01*
X103325Y298992D01*
X102632Y298978D01*
X102590Y298964D01*
X102271Y298950D01*
X102230Y298936D01*
X102161Y298909D01*
X102064Y298881D01*
X101925Y298867D01*
X101869Y298853D01*
X101758Y298839D01*
X101578Y298756D01*
X101523Y298742D01*
X101405Y298721D01*
X101315Y298687D01*
X101162Y298617D01*
X101107Y298603D01*
X100996Y298590D01*
X100871Y298520D01*
X100774Y298479D01*
X100684Y298444D01*
X100600Y298375D01*
X100580Y298354D01*
X100552Y298340D01*
X100524Y298312D01*
X100503Y298305D01*
X100490Y298278D01*
X100399Y298188D01*
X100372Y298174D01*
X100302Y298104D01*
X100233Y298076D01*
X100143Y298042D01*
X100094Y298007D01*
X100025Y297938D01*
X99997Y297924D01*
X99921Y297848D01*
X99907Y297820D01*
X99859Y297785D01*
X99810Y297737D01*
X99796Y297709D01*
X99754Y297667D01*
X99748Y297647D01*
X99727Y297640D01*
X99713Y297612D01*
X99685Y297543D01*
X99650Y297453D01*
X99560Y297362D01*
X99546Y297335D01*
X99484Y297258D01*
X99449Y297224D01*
X99422Y297154D01*
X99387Y297064D01*
X99332Y296981D01*
X99269Y296835D01*
X99214Y296738D01*
X99130Y296558D01*
X99061Y296406D01*
X99047Y296350D01*
X99026Y296177D01*
X98999Y295899D01*
X98985Y295816D01*
X98971Y295747D01*
X98957Y295691D01*
X98936Y295615D01*
X98922Y295560D01*
X98895Y295393D01*
X98881Y295254D01*
X98895Y295157D01*
X98916Y295026D01*
X98929Y294956D01*
X98943Y294901D01*
X98978Y294783D01*
X98992Y294727D01*
X99006Y294630D01*
X99019Y294492D01*
X99040Y294360D01*
X99054Y294305D01*
X99096Y294193D01*
X99130Y294103D01*
X99144Y294048D01*
X99165Y293930D01*
X99193Y293861D01*
X99214Y293840D01*
X99255Y293743D01*
X99290Y293653D01*
X99311Y293604D01*
X99380Y293535D01*
X99394Y293507D01*
X99422Y293479D01*
X99463Y293410D01*
X99484Y293389D01*
X99505Y293382D01*
X99519Y293354D01*
X99546Y293285D01*
X99581Y293195D01*
X99657Y293119D01*
X99671Y293091D01*
X99838Y292925D01*
X99845Y292904D01*
X99872Y292890D01*
X100101Y292661D01*
X100108Y292640D01*
X100136Y292626D01*
X100302Y292460D01*
X100330Y292446D01*
X100399Y292377D01*
X100552Y292321D01*
X100635Y292238D01*
X100663Y292224D01*
X100788Y292127D01*
X100912Y292072D01*
X101037Y292002D01*
X101065Y291975D01*
X101120Y291961D01*
X101190Y291933D01*
X101426Y291822D01*
X101550Y291808D01*
X101620Y291780D01*
X101758Y291739D01*
X101814Y291725D01*
X102258Y291711D01*
X102299Y291697D01*
X102764Y291690D01*
X102799Y291697D01*
X102840Y291683D01*
X113241Y291670D01*
X113283Y291656D01*
X113699Y291642D01*
X113740Y291628D01*
X113816Y291607D01*
X113907Y291572D01*
X114101Y291545D01*
X114212Y291531D01*
X114281Y291503D01*
X114434Y291434D01*
X114531Y291420D01*
X114621Y291399D01*
X114690Y291371D01*
X114711Y291351D01*
X114739Y291337D01*
X114864Y291281D01*
X114954Y291247D01*
X114974Y291226D01*
X115002Y291212D01*
X115071Y291170D01*
X115162Y291136D01*
X115231Y291108D01*
X115266Y291073D01*
X115293Y291059D01*
X115391Y291018D01*
X115460Y290990D01*
X115536Y290928D01*
X115571Y290893D01*
X115598Y290879D01*
X115661Y290817D01*
X115675Y290789D01*
X115709Y290754D01*
X115737Y290740D01*
X115814Y290678D01*
X115848Y290643D01*
X116001Y290588D01*
X116174Y290415D01*
X116195Y290338D01*
X116223Y290269D01*
X116299Y290193D01*
X116313Y290165D01*
X116375Y290089D01*
X116403Y290075D01*
X116479Y289998D01*
X116486Y289978D01*
X116514Y289964D01*
X116590Y289888D01*
X116604Y289860D01*
X116687Y289777D01*
X116715Y289707D01*
X116750Y289617D01*
X116784Y289569D01*
X116854Y289499D01*
X116895Y289430D01*
X116958Y289354D01*
X116978Y289291D01*
X116992Y289194D01*
X117006Y289111D01*
X117075Y289014D01*
X117110Y288924D01*
X117152Y288813D01*
X117179Y288743D01*
X117200Y288681D01*
X117214Y288626D01*
X117235Y288244D01*
X117256Y287419D01*
X117242Y287377D01*
X117235Y287010D01*
X117242Y286878D01*
X117228Y286837D01*
X117207Y286455D01*
X117193Y286386D01*
X117166Y286317D01*
X117131Y286199D01*
X117117Y286143D01*
X117103Y286046D01*
X117048Y285949D01*
X116992Y285824D01*
X116909Y285672D01*
X116854Y285547D01*
X116770Y285394D01*
X116729Y285297D01*
X116659Y285173D01*
X116590Y285103D01*
X116576Y285075D01*
X116500Y284999D01*
X116472Y284985D01*
X116438Y284937D01*
X116389Y284888D01*
X116361Y284874D01*
X116327Y284840D01*
X116313Y284812D01*
X116250Y284750D01*
X116223Y284736D01*
X116202Y284715D01*
X116188Y284687D01*
X116112Y284611D01*
X116084Y284597D01*
X116063Y284576D01*
X116049Y284548D01*
X115848Y284347D01*
X115820Y284333D01*
X115800Y284313D01*
X115786Y284285D01*
X115723Y284223D01*
X115696Y284209D01*
X115612Y284125D01*
X115543Y284098D01*
X115453Y284063D01*
X115404Y284028D01*
X115391Y284001D01*
X115363Y283987D01*
X115238Y283890D01*
X115196Y283848D01*
X115023Y283786D01*
X115002Y283765D01*
X114877Y283709D01*
X114822Y283696D01*
X114690Y283675D01*
X114489Y283571D01*
X114350Y283515D01*
X114226Y283460D01*
X114052Y283439D01*
X113900Y283425D01*
X113775Y283411D01*
X113595Y283384D01*
X113539Y283370D01*
X113477Y283349D01*
X113338Y283335D01*
X112811Y283307D01*
X112305Y283300D01*
X112284Y283307D01*
X112242Y283293D01*
X95275Y283286D01*
X95240Y283293D01*
X95199Y283279D01*
X94589Y283266D01*
X94547Y283252D01*
X94270Y283238D01*
X94145Y283182D01*
X94076Y283155D01*
X93951Y283085D01*
X93826Y283030D01*
X93673Y282947D01*
X93549Y282891D01*
X93396Y282808D01*
X93299Y282766D01*
X93174Y282697D01*
X93119Y282642D01*
X93091Y282628D01*
X93042Y282593D01*
X93029Y282565D01*
X92952Y282489D01*
X92925Y282475D01*
X92841Y282392D01*
X92772Y282364D01*
X92682Y282330D01*
X92564Y282212D01*
X92543Y282205D01*
X92529Y282177D01*
X92488Y282080D01*
X92432Y281983D01*
X92363Y281914D01*
X92321Y281844D01*
X92252Y281775D01*
X92197Y281622D01*
X92148Y281560D01*
X92127Y281553D01*
X92113Y281525D01*
X92016Y281400D01*
X91988Y281373D01*
X91961Y281303D01*
X91926Y281213D01*
X91850Y281068D01*
X91836Y281012D01*
X91822Y280915D01*
X91774Y280783D01*
X91711Y280638D01*
X91690Y280450D01*
X91676Y280367D01*
X91663Y280312D01*
X91621Y280201D01*
X91607Y280145D01*
X91593Y280062D01*
X91566Y279729D01*
X91559Y279681D01*
X91572Y279639D01*
X91593Y279341D01*
X91607Y279258D01*
X91621Y279202D01*
X91649Y279133D01*
X91670Y279057D01*
X91683Y279001D01*
X91697Y278863D01*
X91711Y278807D01*
X91725Y278710D01*
X91808Y278530D01*
X91857Y278315D01*
X91947Y278141D01*
X91981Y278051D01*
X92016Y278003D01*
X92044Y277975D01*
X92058Y277947D01*
X92086Y277920D01*
X92099Y277892D01*
X92127Y277864D01*
X92141Y277836D01*
X92210Y277767D01*
X92231Y277691D01*
X92259Y277621D01*
X92335Y277545D01*
X92349Y277517D01*
X92377Y277490D01*
X92391Y277462D01*
X92439Y277427D01*
X92515Y277351D01*
X92522Y277330D01*
X92550Y277316D01*
X92779Y277087D01*
X92793Y277060D01*
X92841Y277025D01*
X92918Y276949D01*
X92925Y276928D01*
X92952Y276914D01*
X93042Y276824D01*
X93049Y276803D01*
X93077Y276789D01*
X93119Y276748D01*
X93146Y276734D01*
X93216Y276665D01*
X93389Y276602D01*
X93410Y276581D01*
X93438Y276567D01*
X93465Y276540D01*
X93521Y276526D01*
X93618Y276484D01*
X93757Y276401D01*
X93826Y276373D01*
X93916Y276339D01*
X94062Y276262D01*
X94117Y276248D01*
X94235Y276228D01*
X94346Y276186D01*
X94506Y276138D01*
X94603Y276124D01*
X94908Y276110D01*
X94949Y276096D01*
X95150Y276075D01*
X95233Y276061D01*
X95344Y276034D01*
X95497Y276020D01*
X96114Y275985D01*
X97418Y275971D01*
X107458Y275957D01*
X107500Y275943D01*
X107874Y275930D01*
X107943Y275902D01*
X108041Y275860D01*
X108138Y275846D01*
X108193Y275833D01*
X108269Y275812D01*
X108429Y275735D01*
X108526Y275708D01*
X108637Y275694D01*
X108734Y275638D01*
X108886Y275569D01*
X108956Y275541D01*
X109053Y275472D01*
X109185Y275423D01*
X109254Y275382D01*
X109268Y275354D01*
X109330Y275306D01*
X109358Y275292D01*
X109406Y275243D01*
X109420Y275215D01*
X109455Y275181D01*
X109483Y275167D01*
X109559Y275104D01*
X109608Y275056D01*
X109712Y275035D01*
X109760Y275014D01*
X109781Y274993D01*
X109795Y274938D01*
X109816Y274848D01*
X109850Y274799D01*
X109927Y274778D01*
X109996Y274765D01*
X110044Y274730D01*
X110072Y274633D01*
X110086Y274577D01*
X110169Y274494D01*
X110183Y274466D01*
X110246Y274390D01*
X110322Y274328D01*
X110384Y274238D01*
X110412Y274224D01*
X110433Y274203D01*
X110461Y274134D01*
X110474Y274078D01*
X110530Y273981D01*
X110557Y273953D01*
X110585Y273884D01*
X110620Y273794D01*
X110689Y273683D01*
X110724Y273607D01*
X110772Y273475D01*
X110793Y273454D01*
X110849Y273329D01*
X110863Y273232D01*
X110877Y273177D01*
X110946Y272997D01*
X110960Y272941D01*
X110981Y272754D01*
X110994Y272643D01*
X111008Y272449D01*
X111022Y272282D01*
X111036Y272213D01*
X111078Y272102D01*
X111105Y272033D01*
X111126Y271956D01*
X111112Y271804D01*
X111057Y271679D01*
X111015Y271513D01*
X110994Y271187D01*
X110967Y270965D01*
X110953Y270840D01*
X110877Y270653D01*
X110863Y270556D01*
X110849Y270500D01*
X110814Y270410D01*
X110738Y270237D01*
X110717Y270105D01*
X110689Y270036D01*
X110627Y269932D01*
X110571Y269779D01*
X110509Y269703D01*
X110474Y269668D01*
X110461Y269641D01*
X110398Y269564D01*
X110363Y269529D01*
X110336Y269460D01*
X110301Y269370D01*
X110211Y269280D01*
X110169Y269211D01*
X110148Y269190D01*
X110121Y269176D01*
X110058Y269114D01*
X110044Y269086D01*
X110024Y269065D01*
X109996Y269051D01*
X109906Y268961D01*
X109899Y268940D01*
X109871Y268926D01*
X109767Y268822D01*
X109760Y268801D01*
X109732Y268788D01*
X109656Y268711D01*
X109642Y268684D01*
X109621Y268663D01*
X109594Y268649D01*
X109531Y268587D01*
X109517Y268559D01*
X109483Y268524D01*
X109455Y268510D01*
X109393Y268448D01*
X109379Y268420D01*
X109344Y268385D01*
X109316Y268372D01*
X109240Y268309D01*
X109205Y268274D01*
X109074Y268226D01*
X109025Y268205D01*
X108997Y268177D01*
X108970Y268164D01*
X108873Y268122D01*
X108803Y268094D01*
X108706Y268039D01*
X108609Y267997D01*
X108512Y267983D01*
X108436Y267962D01*
X108366Y267935D01*
X108304Y267914D01*
X108249Y267900D01*
X108068Y267886D01*
X107638Y267872D01*
X107292Y267858D01*
X66388Y267852D01*
X66326Y267858D01*
X66284Y267845D01*
X66056Y267852D01*
X65813Y267845D01*
X65785Y267858D01*
X65743Y267845D01*
X65203Y267803D01*
X65120Y267789D01*
X65036Y267734D01*
X65009Y267720D01*
X64932Y267657D01*
X64849Y267477D01*
X64828Y267151D01*
X64814Y266957D01*
X64808Y266742D01*
X64821Y266714D01*
X64808Y266673D01*
X64801Y266000D01*
X64808Y263247D01*
X64794Y263206D01*
X64780Y262041D01*
X64766Y261999D01*
X64752Y261653D01*
X64683Y261500D01*
X64648Y261410D01*
X64620Y261354D01*
X64592Y261341D01*
X64516Y261264D01*
X64502Y261236D01*
X64426Y261202D01*
X64294Y261153D01*
X64218Y261119D01*
X64121Y261105D01*
X63740Y261084D01*
X63171Y261070D01*
X53790Y261063D01*
X53748Y261077D01*
X52999Y261091D01*
X52957Y261105D01*
X52722Y261119D01*
X52569Y261188D01*
X52479Y261223D01*
X52403Y261299D01*
X52375Y261313D01*
X52299Y261375D01*
X52243Y261458D01*
X52229Y261486D01*
X52188Y261583D01*
X52181Y261798D01*
X52188Y261902D01*
X52174Y261944D01*
X52160Y261999D01*
X52167Y262214D01*
X52146Y262360D01*
X52160Y262401D01*
X52153Y262644D01*
X52160Y262817D01*
X52146Y262859D01*
X52160Y263067D01*
X52146Y263109D01*
X52132Y264662D01*
X52118Y264704D01*
X52105Y265106D01*
X52049Y265231D01*
X52021Y265300D01*
X52007Y265355D01*
X51938Y265452D01*
X51834Y265556D01*
X51779Y265570D01*
X51744Y265577D01*
X51688Y265563D01*
X51605Y265494D01*
X51522Y265411D01*
X51494Y265341D01*
X51446Y265210D01*
X51411Y265119D01*
X51397Y265064D01*
X51383Y264634D01*
X51370Y264593D01*
X51356Y263497D01*
X51349Y262408D01*
X51356Y262290D01*
X51342Y262249D01*
X51349Y262020D01*
X51335Y261951D01*
X51321Y261729D01*
X51307Y261549D01*
X51203Y261375D01*
X51155Y261327D01*
X51127Y261313D01*
X51044Y261230D01*
X50974Y261202D01*
X50842Y261153D01*
X50766Y261119D01*
X50711Y261105D01*
X50274Y261084D01*
X49719Y261070D01*
X45940Y261063D01*
X45899Y261077D01*
X45136Y261091D01*
X45094Y261105D01*
X44872Y261119D01*
X44748Y261174D01*
X44658Y261209D01*
X44581Y261257D01*
X44526Y261313D01*
X44498Y261327D01*
X44422Y261403D01*
X44408Y261431D01*
X44352Y261514D01*
X44338Y261569D01*
X44318Y261937D01*
X44304Y262006D01*
X44297Y262110D01*
X44311Y262152D01*
X44297Y262401D01*
X44311Y262443D01*
X44297Y262665D01*
X44290Y266083D01*
X44297Y266243D01*
X44283Y266284D01*
X44297Y266520D01*
X44283Y266562D01*
X44269Y266659D01*
X44248Y267054D01*
X44234Y267137D01*
X44200Y267214D01*
X44137Y267387D01*
X44117Y267408D01*
X44103Y267435D01*
X44033Y267505D01*
X44019Y267533D01*
X43957Y267595D01*
X43888Y267637D01*
X43846Y267678D01*
X43777Y267706D01*
X43576Y267741D01*
X43527Y267775D01*
X43402Y267831D01*
X43278Y267817D01*
X43180Y267747D01*
X43111Y267720D01*
X43021Y267685D01*
X42959Y267623D01*
X42931Y267609D01*
X42903Y267581D01*
X42875Y267567D01*
X42827Y267519D01*
X42813Y267491D01*
X42778Y267456D01*
X42751Y267442D01*
X42702Y267394D01*
X42647Y267297D01*
X42619Y267227D01*
X42605Y267172D01*
X42619Y267117D01*
X42605Y266978D01*
X42577Y266631D01*
X42563Y266590D01*
X42577Y266493D01*
X42570Y266264D01*
X42577Y266104D01*
X42563Y266063D01*
X42570Y265889D01*
X42557Y264988D01*
X42550Y264939D01*
X42563Y264898D01*
X42550Y264717D01*
X42529Y264170D01*
X42515Y264059D01*
X42487Y263989D01*
X42439Y263871D01*
X42425Y263816D01*
X42362Y263740D01*
X42328Y263705D01*
X42314Y263677D01*
X42251Y263601D01*
X42127Y263504D01*
X41877Y263393D01*
X41766Y263365D01*
X41315Y263344D01*
X41267Y263337D01*
X41225Y263351D01*
X41045Y263337D01*
X39616Y263324D01*
X39270Y263337D01*
X38819Y263344D01*
X38757Y263337D01*
X38715Y263351D01*
X38264Y263372D01*
X38209Y263386D01*
X38063Y263449D01*
X37973Y263483D01*
X37952Y263504D01*
X37925Y263518D01*
X37855Y263587D01*
X37827Y263601D01*
X37765Y263663D01*
X37751Y263691D01*
X37682Y263761D01*
X37668Y263788D01*
X37626Y263885D01*
X37592Y263975D01*
X37557Y264052D01*
X37543Y264190D01*
X37515Y265119D01*
X37502Y266423D01*
X37488Y267657D01*
X37439Y267706D01*
X37349Y267727D01*
X37238Y267768D01*
X37162Y267803D01*
X36794Y267824D01*
X36572Y267838D01*
X35726Y267852D01*
X29840Y267858D01*
X29798Y267845D01*
X28772Y267831D01*
X28730Y267817D01*
X28390Y267796D01*
X28321Y267768D01*
X28245Y267734D01*
X28155Y267713D01*
X28106Y267692D01*
X28071Y267657D01*
X28058Y267560D01*
X28051Y263643D01*
X28058Y263469D01*
X28044Y263428D01*
X28058Y263220D01*
X28044Y263178D01*
X28051Y262949D01*
X28037Y262894D01*
X28023Y262810D01*
X28016Y262748D01*
X28030Y262720D01*
X28016Y262679D01*
X28002Y262457D01*
X27940Y262381D01*
X27884Y262325D01*
X27787Y262297D01*
X27434Y262277D01*
X27364Y262263D01*
X27302Y262256D01*
X27260Y262270D01*
X27170Y262277D01*
X27059Y262263D01*
X27038Y262256D01*
X26997Y262270D01*
X26740Y262263D01*
X26553Y262270D01*
X26511Y262256D01*
X26331Y262270D01*
X26290Y262256D01*
X20236Y262263D01*
X20118Y262256D01*
X20077Y262270D01*
X19848Y262263D01*
X19633Y262270D01*
X19605Y262256D01*
X19564Y262270D01*
X19473Y262277D01*
X19362Y262263D01*
X19300Y262256D01*
X19259Y262270D01*
X19161Y262284D01*
X18836Y262304D01*
X18766Y262332D01*
X18669Y262429D01*
X18641Y262498D01*
X18628Y262887D01*
X18614Y262928D01*
X18600Y262984D01*
X18614Y263164D01*
X18600Y263303D01*
X18614Y263400D01*
X18600Y263580D01*
X18614Y263691D01*
X18600Y263733D01*
Y265660D01*
Y265674D01*
X18607Y266610D01*
X18600Y266770D01*
X18614Y266811D01*
X18600Y267033D01*
X18614Y267075D01*
X18607Y267304D01*
X18621Y267359D01*
X18634Y267428D01*
X18648Y267775D01*
X18718Y267886D01*
X18766Y267962D01*
X18787Y267983D01*
X18884Y268039D01*
X18981Y268080D01*
X19224Y268087D01*
X19272Y268080D01*
X19314Y268094D01*
X19418Y268115D01*
X19522Y268122D01*
X19564Y268108D01*
X19813Y268122D01*
X19855Y268108D01*
X20077Y268122D01*
X20153Y268115D01*
X24369Y268129D01*
X24417Y268150D01*
X24438Y268171D01*
X24452Y268226D01*
X24466Y268323D01*
X24452Y274161D01*
X24403Y274224D01*
X24306Y274238D01*
X20264Y274245D01*
X20104Y274238D01*
X20063Y274251D01*
X19834Y274245D01*
X19661Y274251D01*
X19619Y274238D01*
X19522Y274251D01*
X19293Y274245D01*
X19224Y274258D01*
X18988Y274272D01*
X18822Y274286D01*
X18745Y274335D01*
X18655Y274425D01*
X18641Y274522D01*
X18614Y274924D01*
X18600Y274966D01*
X18614Y275243D01*
X18600Y275285D01*
X18614Y275507D01*
X18628Y275548D01*
X18648Y275902D01*
X18683Y275950D01*
X18704Y275985D01*
X18731Y275999D01*
X18773Y276040D01*
X18842Y276068D01*
X19210Y276089D01*
X19265Y276103D01*
X19383Y276110D01*
X19425Y276096D01*
X19668Y276103D01*
X19799Y276096D01*
X19841Y276110D01*
X19973Y276103D01*
X19993Y276110D01*
X20007Y276096D01*
X20049Y276110D01*
X24390Y276124D01*
X24438Y276158D01*
X24466Y276269D01*
X24452Y282149D01*
X24403Y282212D01*
X24306Y282225D01*
X20084Y282232D01*
X19952Y282225D01*
X19910Y282239D01*
X19695Y282232D01*
X19612Y282246D01*
X19605Y282253D01*
X19564Y282239D01*
X19425Y282225D01*
X19383Y282239D01*
X19272Y282267D01*
X18926Y282281D01*
X18898Y282309D01*
X18870Y282323D01*
X18752Y282399D01*
X18738Y282427D01*
X18669Y282524D01*
X18641Y282593D01*
X18621Y282960D01*
X18607Y283044D01*
X18600Y283217D01*
X18614Y283259D01*
X18600Y283536D01*
X18614Y283578D01*
X18628Y283758D01*
X18655Y284049D01*
X18773Y284167D01*
X18884Y284195D01*
X18960Y284188D01*
X19196Y284202D01*
X19252Y284216D01*
X19411Y284223D01*
X19453Y284209D01*
X19633Y284223D01*
X24376Y284236D01*
X24438Y284285D01*
X24452Y284340D01*
X24466Y284438D01*
X24452Y290276D01*
X24424Y290304D01*
X24417Y290324D01*
X24320Y290352D01*
X19848Y290359D01*
X19675Y290352D01*
X19633Y290366D01*
X19397Y290352D01*
X19328Y290380D01*
X18939Y290394D01*
X18842Y290463D01*
X18773Y290505D01*
X18738Y290539D01*
X18724Y290567D01*
X18655Y290678D01*
X18641Y290734D01*
X18621Y291018D01*
X18607Y291157D01*
X18600Y291455D01*
X18614Y291496D01*
X18628Y291857D01*
X18641Y291898D01*
X18655Y292037D01*
X18724Y292190D01*
X18745Y292280D01*
X18766Y292301D01*
X18773Y292321D01*
X18842Y292349D01*
X24403Y292363D01*
X24438Y292398D01*
X24452Y292453D01*
X24466Y292550D01*
X24452Y298389D01*
X24403Y298451D01*
X24348Y298465D01*
X19931Y298472D01*
X19841Y298465D01*
X19799Y298479D01*
X19570Y298472D01*
X19501Y298486D01*
X19453Y298493D01*
X19411Y298479D01*
X19314Y298465D01*
X19147Y298506D01*
X18787Y298520D01*
X18655Y298652D01*
X18641Y298749D01*
X18628Y299096D01*
X18614Y299137D01*
X18600Y299193D01*
X18614Y299373D01*
X18600Y299512D01*
X18614Y299609D01*
X18600Y299789D01*
X18614Y299914D01*
X18600Y299956D01*
X18614Y321978D01*
X18628Y322019D01*
X18648Y322470D01*
X18662Y322526D01*
X18711Y322643D01*
X18738Y322741D01*
X18780Y322810D01*
X18856Y322831D01*
X94644Y322817D01*
D02*
G37*
G36*
X21907Y297785D02*
X21949Y297771D01*
X22143Y297757D01*
X22295Y297688D01*
X22365Y297661D01*
X22490Y297591D01*
X22615Y297536D01*
X22739Y297466D01*
X22864Y297411D01*
X22989Y297341D01*
X23017Y297300D01*
X23044Y297286D01*
X23121Y297224D01*
X23183Y297134D01*
X23211Y297120D01*
X23232Y297099D01*
X23259Y297029D01*
X23280Y296953D01*
X23315Y296905D01*
X23384Y296835D01*
X23398Y296808D01*
X23460Y296731D01*
X23495Y296697D01*
X23509Y296669D01*
X23537Y296600D01*
X23571Y296509D01*
X23634Y296406D01*
X23661Y296294D01*
X23682Y296177D01*
X23745Y296017D01*
X23772Y295823D01*
X23793Y295428D01*
X23800Y295282D01*
X23786Y295240D01*
X23772Y294852D01*
X23759Y294811D01*
X23745Y294658D01*
X23675Y294506D01*
X23641Y294415D01*
X23592Y294339D01*
X23523Y294187D01*
X23454Y294062D01*
X23398Y293937D01*
X23342Y293840D01*
X23287Y293784D01*
X23273Y293757D01*
X23211Y293680D01*
X23183Y293666D01*
X23135Y293618D01*
X23121Y293590D01*
X23072Y293542D01*
X23003Y293500D01*
X22933Y293431D01*
X22878Y293417D01*
X22788Y293382D01*
X22698Y293292D01*
X22601Y293237D01*
X22545Y293181D01*
X22476Y293153D01*
X22427Y293146D01*
X22420Y293140D01*
X22295Y293126D01*
X22115Y293043D01*
X22004Y293015D01*
X21810Y293001D01*
X21741Y292973D01*
X21651Y292938D01*
X21574Y292918D01*
X21519Y292904D01*
X21422Y292890D01*
X21366Y292876D01*
X21186Y292890D01*
X21144Y292904D01*
X21054Y292925D01*
X20985Y292952D01*
X20826Y293001D01*
X20687Y293015D01*
X20576Y293029D01*
X20340Y293140D01*
X20250Y293174D01*
X20229Y293195D01*
X20201Y293209D01*
X20118Y293264D01*
X20042Y293285D01*
X19993Y293306D01*
X19917Y293368D01*
X19883Y293403D01*
X19855Y293417D01*
X19792Y293479D01*
X19778Y293507D01*
X19744Y293542D01*
X19716Y293556D01*
X19668Y293604D01*
X19654Y293632D01*
X19619Y293666D01*
X19591Y293680D01*
X19529Y293743D01*
X19515Y293771D01*
X19480Y293805D01*
X19453Y293819D01*
X19404Y293868D01*
X19390Y293895D01*
X19307Y293979D01*
X19293Y294006D01*
X19265Y294076D01*
X19252Y294131D01*
X19154Y294270D01*
X19134Y294346D01*
X19106Y294415D01*
X19044Y294533D01*
X19016Y294630D01*
X18967Y294928D01*
X18946Y294977D01*
X18919Y295046D01*
X18905Y295102D01*
X18891Y295199D01*
X18877Y295338D01*
X18891Y295657D01*
X18905Y295698D01*
X18919Y295795D01*
X18988Y295948D01*
X19002Y296128D01*
X19037Y296274D01*
X19113Y296419D01*
X19147Y296509D01*
X19175Y296579D01*
X19210Y296614D01*
X19224Y296641D01*
X19265Y296738D01*
X19300Y296828D01*
X19390Y296919D01*
X19404Y296946D01*
X19605Y297147D01*
X19633Y297161D01*
X19654Y297182D01*
X19668Y297210D01*
X19883Y297425D01*
X19910Y297439D01*
X19980Y297508D01*
X20049Y297536D01*
X20139Y297570D01*
X20285Y297647D01*
X20396Y297674D01*
X20500Y297695D01*
X20617Y297744D01*
X20673Y297757D01*
X20812Y297771D01*
X20992Y297785D01*
X21297Y297799D01*
X21907Y297785D01*
D02*
G37*
G36*
X21588Y289797D02*
X21734Y289777D01*
X21789Y289763D01*
X21866Y289728D01*
X21963Y289700D01*
X22122Y289680D01*
X22205Y289666D01*
X22261Y289652D01*
X22406Y289576D01*
X22538Y289527D01*
X22615Y289478D01*
X22642Y289451D01*
X22816Y289388D01*
X22906Y289298D01*
X22933Y289284D01*
X22968Y289263D01*
X22982Y289236D01*
X23273Y288944D01*
X23287Y288917D01*
X23370Y288834D01*
X23419Y288702D01*
X23488Y288591D01*
X23523Y288515D01*
X23558Y288424D01*
X23627Y288314D01*
X23675Y288196D01*
X23710Y288106D01*
X23745Y288029D01*
X23759Y287932D01*
X23786Y287558D01*
X23800Y287267D01*
X23786Y287225D01*
X23765Y286816D01*
X23738Y286649D01*
X23689Y286532D01*
X23661Y286421D01*
X23648Y286324D01*
X23592Y286226D01*
X23537Y286102D01*
X23502Y286012D01*
X23412Y285921D01*
X23398Y285894D01*
X23336Y285817D01*
X23301Y285783D01*
X23259Y285686D01*
X23245Y285630D01*
X23183Y285554D01*
X23155Y285540D01*
X23121Y285505D01*
X23107Y285478D01*
X23086Y285457D01*
X23017Y285429D01*
X22926Y285394D01*
X22878Y285360D01*
X22809Y285290D01*
X22781Y285277D01*
X22705Y285214D01*
X22670Y285179D01*
X22497Y285117D01*
X22476Y285096D01*
X22351Y285041D01*
X22295Y285027D01*
X22178Y285006D01*
X22108Y284978D01*
X22018Y284944D01*
X21879Y284930D01*
X21824Y284916D01*
X21443Y284895D01*
X21242Y284888D01*
X21200Y284902D01*
X20826Y284916D01*
X20784Y284930D01*
X20645Y284944D01*
X20493Y285013D01*
X20403Y285048D01*
X20326Y285096D01*
X20174Y285166D01*
X20049Y285235D01*
X19924Y285290D01*
X19827Y285346D01*
X19772Y285401D01*
X19744Y285415D01*
X19668Y285478D01*
X19654Y285505D01*
X19591Y285568D01*
X19564Y285582D01*
X19543Y285602D01*
X19529Y285630D01*
X19467Y285693D01*
X19439Y285706D01*
X19404Y285741D01*
X19390Y285769D01*
X19328Y285845D01*
X19293Y285880D01*
X19265Y285949D01*
X19252Y286005D01*
X19196Y286102D01*
X19141Y286226D01*
X19113Y286393D01*
X19016Y286601D01*
X19002Y286698D01*
X18974Y286809D01*
X18919Y286934D01*
X18905Y286989D01*
X18891Y287086D01*
X18863Y287391D01*
X18877Y287433D01*
X18898Y287689D01*
X18912Y287759D01*
X18960Y287877D01*
X18988Y287946D01*
X19002Y288043D01*
X19023Y288133D01*
X19127Y288334D01*
X19161Y288424D01*
X19210Y288501D01*
X19265Y288626D01*
X19321Y288723D01*
X19362Y288764D01*
X19376Y288792D01*
X19404Y288820D01*
X19418Y288848D01*
X19439Y288868D01*
X19467Y288882D01*
X19543Y288958D01*
X19557Y288986D01*
X19577Y289007D01*
X19605Y289021D01*
X19681Y289097D01*
X19695Y289125D01*
X19716Y289146D01*
X19744Y289160D01*
X19806Y289222D01*
X19820Y289250D01*
X19855Y289284D01*
X19883Y289298D01*
X19959Y289361D01*
X19993Y289395D01*
X20063Y289423D01*
X20118Y289437D01*
X20271Y289534D01*
X20403Y289583D01*
X20465Y289617D01*
X20479D01*
X20604Y289673D01*
X20742Y289687D01*
X20867Y289700D01*
X20964Y289742D01*
X21034Y289770D01*
X21089Y289783D01*
X21249Y289804D01*
X21547Y289811D01*
X21588Y289797D01*
D02*
G37*
G36*
X126173Y291649D02*
X126228Y291635D01*
X126298Y291621D01*
X126388Y291586D01*
X126499Y291559D01*
X126672Y291538D01*
X126783Y291510D01*
X126852Y291482D01*
X126873Y291462D01*
X127012Y291420D01*
X127123Y291406D01*
X127331Y291309D01*
X127442Y291281D01*
X127553Y291267D01*
X127629Y291205D01*
X127663Y291170D01*
X127761Y291115D01*
X127830Y291045D01*
X127899Y291018D01*
X127920Y291011D01*
X127927Y291004D01*
X127983Y290990D01*
X128066Y290907D01*
X128093Y290893D01*
X128121Y290865D01*
X128149Y290851D01*
X128184Y290803D01*
X128246Y290740D01*
X128274Y290727D01*
X128343Y290657D01*
X128371Y290643D01*
X128440Y290616D01*
X128496Y290602D01*
X128572Y290539D01*
X128620Y290491D01*
X128648Y290477D01*
X128724Y290401D01*
X128738Y290373D01*
X128759Y290352D01*
X128787Y290338D01*
X128849Y290276D01*
X128863Y290248D01*
X128933Y290179D01*
X128946Y290151D01*
X128974Y290082D01*
X128988Y290026D01*
X129016Y289998D01*
X129030Y289971D01*
X129099Y289901D01*
X129113Y289874D01*
X129175Y289797D01*
X129210Y289763D01*
X129258Y289631D01*
X129293Y289583D01*
X129335Y289541D01*
X129348Y289513D01*
X129446Y289388D01*
X129473Y289361D01*
X129501Y289250D01*
X129515Y289139D01*
X129612Y288931D01*
X129640Y288820D01*
X129654Y288723D01*
X129737Y288542D01*
X129758Y288466D01*
X129771Y288314D01*
X129785Y288230D01*
X129806Y288154D01*
X129834Y288085D01*
X129862Y287988D01*
X129875Y287849D01*
X129903Y287474D01*
X129882Y287204D01*
X129868Y287038D01*
X129855Y286954D01*
X129813Y286843D01*
X129799Y286788D01*
X129778Y286712D01*
X129764Y286573D01*
X129751Y286476D01*
X129737Y286434D01*
X129668Y286282D01*
X129640Y286185D01*
X129626Y286074D01*
X129487Y285783D01*
X129432Y285686D01*
X129348Y285505D01*
X129293Y285408D01*
X129238Y285283D01*
X129182Y285186D01*
X129127Y285131D01*
X129113Y285103D01*
X129064Y285041D01*
X129037Y285027D01*
X128946Y284937D01*
X128939Y284916D01*
X128912Y284902D01*
X128821Y284812D01*
X128808Y284784D01*
X128724Y284715D01*
X128281Y284271D01*
X128274Y284250D01*
X128246Y284236D01*
X128156Y284146D01*
X128142Y284118D01*
X128093Y284084D01*
X128017Y284021D01*
X127983Y283987D01*
X127913Y283959D01*
X127858Y283945D01*
X127788Y283904D01*
X127761Y283876D01*
X127663Y283834D01*
X127573Y283800D01*
X127497Y283751D01*
X127345Y283682D01*
X127137Y283585D01*
X127081Y283571D01*
X126901Y283557D01*
X126845Y283543D01*
X126714Y283494D01*
X126596Y283460D01*
X126540Y283446D01*
X126402Y283432D01*
X126305Y283418D01*
X126173Y283397D01*
X126117Y283384D01*
X126006Y283342D01*
X125937Y283328D01*
X125826Y283314D01*
X125639Y283293D01*
X125452Y283314D01*
X125341Y283328D01*
X125271Y283342D01*
X125195Y283377D01*
X125119Y283397D01*
X125036Y283411D01*
X124848Y283432D01*
X124703Y283453D01*
X124647Y283467D01*
X124557Y283501D01*
X124460Y283543D01*
X124363Y283557D01*
X124307Y283571D01*
X124217Y283605D01*
X124044Y283682D01*
X123947Y283696D01*
X123864Y283709D01*
X123787Y283772D01*
X123753Y283806D01*
X123656Y283862D01*
X123586Y283931D01*
X123517Y283959D01*
X123427Y283994D01*
X123344Y284049D01*
X123267Y284084D01*
X123156Y284125D01*
X123073Y284209D01*
X123046Y284223D01*
X122955Y284313D01*
X122949Y284333D01*
X122921Y284347D01*
X122366Y284902D01*
X122338Y284916D01*
X122283Y284999D01*
X122206Y285075D01*
X122179Y285145D01*
X122137Y285256D01*
X122109Y285283D01*
X122096Y285311D01*
X122054Y285408D01*
X122019Y285498D01*
X121929Y285588D01*
X121915Y285616D01*
X121846Y285713D01*
X121818Y285741D01*
X121791Y285810D01*
X121777Y285907D01*
X121756Y285984D01*
X121728Y286053D01*
X121652Y286226D01*
X121631Y286358D01*
X121589Y286469D01*
X121569Y286545D01*
X121555Y286601D01*
X121534Y286927D01*
X121520Y287287D01*
X121513Y287683D01*
X121527Y287724D01*
X121541Y288223D01*
X121555Y288265D01*
X121569Y288459D01*
X121610Y288556D01*
X121638Y288653D01*
X121659Y288771D01*
X121686Y288841D01*
X121763Y289000D01*
X121777Y289097D01*
X121797Y289187D01*
X121825Y289256D01*
X121860Y289291D01*
X121902Y289388D01*
X121915Y289444D01*
X121957Y289513D01*
X122026Y289583D01*
X122040Y289610D01*
X122102Y289700D01*
X122123Y289707D01*
X122137Y289735D01*
X122179Y289832D01*
X122234Y289929D01*
X122304Y289998D01*
X122317Y290026D01*
X122935Y290643D01*
X122955Y290650D01*
X122969Y290678D01*
X123059Y290768D01*
X123087Y290782D01*
X123156Y290851D01*
X123226Y290879D01*
X123316Y290914D01*
X123378Y290976D01*
X123406Y290990D01*
X123434Y291018D01*
X123503Y291059D01*
X123573Y291129D01*
X123725Y291184D01*
X123822Y291254D01*
X123954Y291302D01*
X124002Y291323D01*
X124113Y291392D01*
X124280Y291420D01*
X124411Y291469D01*
X124488Y291503D01*
X124599Y291531D01*
X124779Y291545D01*
X124834Y291559D01*
X124973Y291572D01*
X125015Y291586D01*
X125154Y291628D01*
X125209Y291642D01*
X125348Y291656D01*
X125722Y291683D01*
X126173Y291649D01*
D02*
G37*
G36*
X21519Y281685D02*
X21803Y281664D01*
X21872Y281650D01*
X21983Y281608D01*
X22101Y281574D01*
X22157Y281560D01*
X22240Y281546D01*
X22337Y281490D01*
X22462Y281435D01*
X22531Y281407D01*
X22559Y281394D01*
X22656Y281324D01*
X22712Y281310D01*
X22802Y281276D01*
X22878Y281199D01*
X22906Y281185D01*
X22933Y281158D01*
X22961Y281144D01*
X23010Y281095D01*
X23024Y281068D01*
X23058Y281033D01*
X23086Y281019D01*
X23135Y280970D01*
X23148Y280943D01*
X23197Y280894D01*
X23225Y280880D01*
X23259Y280846D01*
X23273Y280818D01*
X23301Y280790D01*
X23315Y280763D01*
X23370Y280707D01*
X23398Y280638D01*
X23412Y280582D01*
X23474Y280506D01*
X23523Y280457D01*
X23578Y280360D01*
X23634Y280305D01*
X23661Y280208D01*
X23675Y280083D01*
X23731Y279958D01*
X23745Y279903D01*
X23759Y279806D01*
X23772Y279667D01*
X23786Y279403D01*
X23800Y279182D01*
X23786Y279043D01*
X23765Y278717D01*
X23752Y278592D01*
X23738Y278537D01*
X23710Y278467D01*
X23675Y278377D01*
X23661Y278322D01*
Y278308D01*
X23648Y278197D01*
X23585Y278121D01*
X23481Y277975D01*
X23440Y277934D01*
X23426Y277906D01*
X23370Y277767D01*
X23308Y277691D01*
X23273Y277656D01*
X23259Y277628D01*
X23197Y277566D01*
X23169Y277552D01*
X23135Y277517D01*
X23121Y277490D01*
X23058Y277427D01*
X23031Y277413D01*
X22996Y277379D01*
X22982Y277351D01*
X22933Y277302D01*
X22906Y277289D01*
X22822Y277205D01*
X22753Y277178D01*
X22663Y277143D01*
X22580Y277074D01*
X22545Y277039D01*
X22448Y276984D01*
X22393Y276928D01*
X22226Y276900D01*
X22094Y276852D01*
X22032Y276831D01*
X21977Y276817D01*
X21879Y276803D01*
X21616Y276789D01*
X21519Y276775D01*
X21006Y276789D01*
X20964Y276803D01*
X20784Y276817D01*
X20687Y276859D01*
X20617Y276886D01*
X20562Y276900D01*
X20444Y276921D01*
X20375Y276949D01*
X20271Y277011D01*
X20139Y277060D01*
X20090Y277094D01*
X20035Y277150D01*
X20007Y277164D01*
X19931Y277226D01*
X19883Y277275D01*
X19709Y277337D01*
X19681Y277365D01*
X19668Y277393D01*
X19584Y277448D01*
X19529Y277504D01*
X19515Y277531D01*
X19432Y277614D01*
X19404Y277684D01*
X19383Y277760D01*
X19362Y277781D01*
X19349Y277809D01*
X19279Y277878D01*
X19265Y277906D01*
X19203Y277982D01*
X19154Y278030D01*
X19092Y278204D01*
X19030Y278308D01*
X19016Y278405D01*
X19002Y278460D01*
X18981Y278634D01*
X18967Y278689D01*
X18933Y278766D01*
X18905Y278863D01*
X18891Y278960D01*
X18877Y279098D01*
X18891Y279417D01*
X18905Y279459D01*
X18919Y279542D01*
X18974Y279667D01*
X18988Y279722D01*
X19002Y279861D01*
X19023Y279993D01*
X19057Y280083D01*
X19113Y280208D01*
X19127Y280263D01*
X19141Y280360D01*
X19154Y280416D01*
X19217Y280492D01*
X19238Y280513D01*
X19252Y280541D01*
X19314Y280617D01*
X19355Y280658D01*
X19376Y280665D01*
X19390Y280693D01*
X19480Y280783D01*
X19508Y280797D01*
X19577Y280880D01*
X19619Y280922D01*
X19640Y280929D01*
X19654Y280957D01*
X19744Y281047D01*
X19772Y281061D01*
X19806Y281109D01*
X19869Y281172D01*
X19896Y281185D01*
X19980Y281269D01*
X20049Y281296D01*
X20139Y281331D01*
X20188Y281366D01*
X20243Y281421D01*
X20271Y281435D01*
X20347Y281497D01*
X20451Y281560D01*
X20590Y281574D01*
X20631Y281588D01*
X20728Y281629D01*
X20826Y281657D01*
X20923Y281671D01*
X21179Y281692D01*
X21477Y281699D01*
X21519Y281685D01*
D02*
G37*
G36*
X21491Y273572D02*
X21817Y273551D01*
X21956Y273537D01*
X22025Y273524D01*
X22094Y273496D01*
X22185Y273461D01*
X22282Y273447D01*
X22337Y273433D01*
X22427Y273399D01*
X22510Y273343D01*
X22663Y273288D01*
X22712Y273253D01*
X22781Y273184D01*
X22809Y273170D01*
X23010Y272969D01*
X23024Y272941D01*
X23072Y272906D01*
X23148Y272830D01*
X23162Y272802D01*
X23211Y272768D01*
X23412Y272567D01*
X23426Y272539D01*
X23495Y272470D01*
X23509Y272442D01*
X23537Y272372D01*
X23571Y272282D01*
X23634Y272178D01*
X23661Y272067D01*
X23682Y271950D01*
X23710Y271880D01*
X23745Y271790D01*
X23759Y271693D01*
X23772Y271513D01*
X23786Y271374D01*
X23800Y271027D01*
X23786Y270986D01*
X23772Y270597D01*
X23759Y270556D01*
X23745Y270417D01*
X23689Y270292D01*
X23661Y270181D01*
X23648Y270084D01*
X23592Y269987D01*
X23537Y269862D01*
X23502Y269772D01*
X23412Y269682D01*
X23398Y269654D01*
X23349Y269592D01*
X23322Y269578D01*
X23121Y269377D01*
X23107Y269349D01*
X23086Y269328D01*
X23058Y269315D01*
X22996Y269252D01*
X22982Y269224D01*
X22947Y269190D01*
X22920Y269176D01*
X22843Y269114D01*
X22809Y269079D01*
X22739Y269051D01*
X22649Y269016D01*
X22601Y268982D01*
X22420Y268899D01*
X22185Y268788D01*
X22060Y268774D01*
X22018Y268760D01*
X21921Y268718D01*
X21824Y268690D01*
X21727Y268677D01*
X21456Y268656D01*
X21228Y268649D01*
X21186Y268663D01*
X20874Y268684D01*
X20805Y268697D01*
X20694Y268739D01*
X20576Y268774D01*
X20520Y268788D01*
X20416Y268808D01*
X20243Y268899D01*
X20153Y268933D01*
X20104Y268954D01*
X20070Y268989D01*
X20063Y269009D01*
X20035Y269023D01*
X20007Y269051D01*
X19980Y269065D01*
X19917Y269127D01*
X19903Y269155D01*
X19883Y269176D01*
X19855Y269190D01*
X19792Y269252D01*
X19778Y269280D01*
X19744Y269315D01*
X19716Y269328D01*
X19668Y269377D01*
X19654Y269405D01*
X19619Y269439D01*
X19591Y269453D01*
X19529Y269516D01*
X19515Y269543D01*
X19480Y269578D01*
X19453Y269592D01*
X19404Y269641D01*
X19390Y269668D01*
X19307Y269751D01*
X19293Y269779D01*
X19265Y269848D01*
X19231Y269939D01*
X19210Y269959D01*
X19196Y269987D01*
X19168Y270015D01*
X19120Y270147D01*
X19092Y270216D01*
X19030Y270320D01*
X19002Y270417D01*
X18981Y270549D01*
X18905Y270736D01*
X18863Y271152D01*
X18877Y271194D01*
X18898Y271450D01*
X18912Y271506D01*
X18953Y271617D01*
X18988Y271707D01*
X19009Y271838D01*
X19023Y271894D01*
X19127Y272095D01*
X19161Y272185D01*
X19210Y272262D01*
X19279Y272414D01*
X19349Y272539D01*
X19404Y272664D01*
X19460Y272761D01*
X19515Y272816D01*
X19529Y272844D01*
X19564Y272892D01*
X19591Y272906D01*
X19619Y272934D01*
X19647Y272948D01*
X19702Y273031D01*
X19730Y273045D01*
X19806Y273107D01*
X19855Y273156D01*
X20028Y273218D01*
X20063Y273253D01*
X20090Y273267D01*
X20097Y273274D01*
X20104Y273281D01*
X20236Y273329D01*
X20306Y273357D01*
X20389Y273412D01*
X20465Y273433D01*
X20562Y273447D01*
X20694Y273496D01*
X20812Y273530D01*
X20867Y273544D01*
X21165Y273565D01*
X21332Y273579D01*
X21450Y273586D01*
X21491Y273572D01*
D02*
G37*
%LPC*%
G36*
X193522Y499450D02*
X190478D01*
X187493Y498856D01*
X184682Y497692D01*
X182151Y496001D01*
X179999Y493849D01*
X178308Y491318D01*
X177687Y489819D01*
X176313D01*
X175692Y491318D01*
X174001Y493849D01*
X171849Y496001D01*
X169318Y497692D01*
X166507Y498856D01*
X163522Y499450D01*
X160478D01*
X157493Y498856D01*
X154682Y497692D01*
X152151Y496001D01*
X149999Y493849D01*
X148308Y491318D01*
X147144Y488507D01*
X146550Y485522D01*
Y482478D01*
X147144Y479493D01*
X148308Y476682D01*
X149999Y474151D01*
X152151Y471999D01*
X154682Y470308D01*
X157493Y469144D01*
X160478Y468550D01*
X163522D01*
X166507Y469144D01*
X169318Y470308D01*
X171849Y471999D01*
X174001Y474151D01*
X175692Y476682D01*
X176313Y478181D01*
X177687D01*
X178308Y476682D01*
X179999Y474151D01*
X182151Y471999D01*
X184682Y470308D01*
X187493Y469144D01*
X190478Y468550D01*
X193522D01*
X196507Y469144D01*
X199318Y470308D01*
X201849Y471999D01*
X204001Y474151D01*
X205692Y476682D01*
X206856Y479493D01*
X207450Y482478D01*
Y485522D01*
X206856Y488507D01*
X205692Y491318D01*
X204001Y493849D01*
X201849Y496001D01*
X199318Y497692D01*
X196507Y498856D01*
X193522Y499450D01*
D02*
G37*
G36*
X306750Y494040D02*
X303960D01*
Y491809D01*
X298775D01*
X297795Y491614D01*
X296965Y491060D01*
X296905Y491000D01*
X296350Y490169D01*
X296156Y489190D01*
X296350Y488211D01*
X296905Y487380D01*
X297735Y486826D01*
X298715Y486631D01*
X299016Y486691D01*
X303960D01*
Y484460D01*
X306750D01*
Y489250D01*
Y494040D01*
D02*
G37*
G36*
X348040Y493540D02*
X345250D01*
Y488750D01*
Y483960D01*
X348040D01*
Y486191D01*
X351500D01*
X352479Y486386D01*
X353310Y486940D01*
X353864Y487771D01*
X354059Y488750D01*
X353864Y489729D01*
X353310Y490560D01*
X352479Y491114D01*
X351500Y491309D01*
X348040D01*
Y493540D01*
D02*
G37*
G36*
X341250D02*
X338460D01*
Y493000D01*
X331000D01*
Y488119D01*
X328190Y485310D01*
X327636Y484479D01*
X327441Y483500D01*
Y478300D01*
X324750D01*
Y461800D01*
X335250D01*
Y478300D01*
X332559D01*
Y482440D01*
X334619Y484500D01*
X338460D01*
Y483960D01*
X341250D01*
Y488750D01*
Y493540D01*
D02*
G37*
G36*
X73639Y496450D02*
X70361D01*
X67194Y495602D01*
X64356Y493963D01*
X62038Y491645D01*
X60399Y488806D01*
X59550Y485639D01*
Y482361D01*
X60399Y479194D01*
X62038Y476356D01*
X64356Y474038D01*
X67194Y472398D01*
X70361Y471550D01*
X73639D01*
X76806Y472398D01*
X79644Y474038D01*
X81962Y476356D01*
X83602Y479194D01*
X84450Y482361D01*
Y485639D01*
X83602Y488806D01*
X81962Y491645D01*
X79644Y493963D01*
X76806Y495602D01*
X73639Y496450D01*
D02*
G37*
G36*
X313540Y494040D02*
X310750D01*
Y489250D01*
Y484460D01*
X313540D01*
Y484460D01*
X314741Y484293D01*
Y478300D01*
X312050D01*
Y461800D01*
X322550D01*
Y478300D01*
X319859D01*
Y485000D01*
X321000D01*
Y493500D01*
X313540D01*
Y494040D01*
D02*
G37*
G36*
X49000Y469912D02*
X45986Y469105D01*
X43024Y467395D01*
X40605Y464976D01*
X38895Y462014D01*
X38088Y459000D01*
X49000D01*
Y469912D01*
D02*
G37*
G36*
X269250Y455590D02*
X263710D01*
Y450300D01*
X269250D01*
Y455590D01*
D02*
G37*
G36*
X290890Y453050D02*
X287250D01*
Y449510D01*
X290890D01*
Y453050D01*
D02*
G37*
G36*
X49000Y455000D02*
X38088D01*
X38895Y451986D01*
X40605Y449024D01*
X43024Y446605D01*
X45986Y444895D01*
X49000Y444088D01*
Y455000D01*
D02*
G37*
G36*
X63912D02*
X53000D01*
Y444088D01*
X56014Y444895D01*
X58976Y446605D01*
X61395Y449024D01*
X63105Y451986D01*
X63912Y455000D01*
D02*
G37*
G36*
X467093Y490118D02*
X392271D01*
X392168Y490097D01*
X387421Y489724D01*
X382690Y488588D01*
X378195Y486726D01*
X374046Y484184D01*
X370425Y481091D01*
X370338Y481033D01*
X362555Y473250D01*
X347950D01*
Y478300D01*
X337450D01*
Y461800D01*
X347500D01*
Y454750D01*
X370000D01*
Y464805D01*
X378283Y473088D01*
X378429Y473306D01*
X381238Y475612D01*
X384671Y477447D01*
X388397Y478577D01*
X392014Y478933D01*
X392271Y478882D01*
X467093D01*
X467245Y478912D01*
X469187Y478657D01*
X471138Y477849D01*
X472692Y476656D01*
X472777Y476527D01*
X475522Y473783D01*
X475746Y473633D01*
X477556Y471274D01*
X478796Y468280D01*
X479184Y465331D01*
X479132Y465068D01*
Y442826D01*
X465883D01*
X465498Y444096D01*
X466849Y444999D01*
X469001Y447151D01*
X470692Y449682D01*
X471856Y452493D01*
X472450Y455478D01*
Y458522D01*
X471856Y461507D01*
X470692Y464318D01*
X469001Y466849D01*
X466849Y469001D01*
X464318Y470692D01*
X461507Y471856D01*
X458522Y472450D01*
X455478D01*
X452493Y471856D01*
X449682Y470692D01*
X447151Y469001D01*
X444999Y466849D01*
X443308Y464318D01*
X442144Y461507D01*
X441550Y458522D01*
Y455478D01*
X442144Y452493D01*
X443308Y449682D01*
X444999Y447151D01*
X447054Y445096D01*
X446984Y444447D01*
X446795Y443826D01*
X439550D01*
Y436008D01*
X438185Y434888D01*
X434752Y433053D01*
X431027Y431923D01*
X427410Y431567D01*
X427153Y431618D01*
X420681D01*
X420428Y432888D01*
X422710Y433833D01*
X426068Y436077D01*
X428923Y438932D01*
X431167Y442290D01*
X432712Y446020D01*
X433500Y449981D01*
Y454019D01*
X432712Y457980D01*
X431167Y461710D01*
X428923Y465068D01*
X426068Y467923D01*
X422710Y470167D01*
X418980Y471712D01*
X415019Y472500D01*
X410981D01*
X407020Y471712D01*
X403290Y470167D01*
X399932Y467923D01*
X397077Y465068D01*
X394833Y461710D01*
X393288Y457980D01*
X392500Y454019D01*
Y449981D01*
X393288Y446020D01*
X394833Y442290D01*
X397077Y438932D01*
X399932Y436077D01*
X403290Y433833D01*
X405572Y432888D01*
X405319Y431618D01*
X384021D01*
X383918Y431598D01*
X379171Y431224D01*
X374440Y430088D01*
X369945Y428226D01*
X365796Y425684D01*
X362175Y422591D01*
X362088Y422533D01*
X362028Y422472D01*
X361902Y422285D01*
X360284Y421204D01*
X358375Y420824D01*
X358154Y420868D01*
X332146D01*
X331660Y422041D01*
X331810Y422190D01*
X332364Y423021D01*
X332559Y424000D01*
Y424300D01*
X335250D01*
Y440800D01*
X324750D01*
Y424300D01*
X325022D01*
X325508Y423127D01*
X323940Y421559D01*
X314588D01*
X314102Y422733D01*
X315669Y424300D01*
X322550D01*
Y440800D01*
X312050D01*
Y427919D01*
X309380Y425249D01*
X274131D01*
X273981Y426519D01*
X275534Y426892D01*
X279558Y428559D01*
X283273Y430835D01*
X285639Y432856D01*
X286585Y433665D01*
X286585Y433665D01*
X287538Y434430D01*
X288226Y434958D01*
X290159Y435759D01*
X291730Y435965D01*
X292931Y435165D01*
X293000Y435079D01*
Y432350D01*
X309500D01*
Y444850D01*
X293000D01*
Y442176D01*
X292234Y441223D01*
X288816Y440773D01*
X285631Y439454D01*
X282895Y437355D01*
X282895Y437355D01*
X281985Y436486D01*
X279532Y434472D01*
X275618Y432380D01*
X271371Y431092D01*
X267059Y430667D01*
X266954Y430688D01*
X248397D01*
X248348Y430678D01*
X246459Y431054D01*
X244815Y432152D01*
X243717Y433796D01*
X243342Y435685D01*
X243351Y435734D01*
Y453000D01*
X244892D01*
Y460019D01*
X255200D01*
X255451Y460069D01*
X264250D01*
Y457550D01*
X278250D01*
Y460069D01*
X279610D01*
Y456520D01*
X278790Y455590D01*
X278340Y455590D01*
X273250D01*
Y448300D01*
Y441010D01*
X278790D01*
Y448580D01*
X279610Y449510D01*
X280060Y449510D01*
X283250D01*
Y455050D01*
X285250D01*
Y457050D01*
X290890D01*
Y460069D01*
X293000D01*
Y457750D01*
X309500D01*
Y470250D01*
X293000D01*
Y468032D01*
X290350D01*
Y469250D01*
X280150D01*
Y468032D01*
X278250D01*
Y471050D01*
X264250D01*
Y468032D01*
X255250D01*
X254999Y467981D01*
X245128D01*
Y475307D01*
X245739Y475918D01*
X246500Y477755D01*
Y479745D01*
X245739Y481582D01*
X244332Y482989D01*
X242495Y483750D01*
X240505D01*
X238668Y482989D01*
X237261Y481582D01*
X236500Y479745D01*
Y477755D01*
X237165Y476151D01*
Y468200D01*
X236692D01*
Y459800D01*
Y453000D01*
X238233D01*
Y435734D01*
X238195D01*
X238543Y433093D01*
X239562Y430633D01*
X241183Y428520D01*
X243296Y426898D01*
X244211Y426519D01*
X243959Y425249D01*
X238750D01*
X238637Y425522D01*
X237230Y426929D01*
X235392Y427690D01*
X233403D01*
X231566Y426929D01*
X230159Y425522D01*
X229398Y423685D01*
Y421696D01*
X230159Y419858D01*
X230900Y419117D01*
X230374Y417847D01*
X227724D01*
X227611Y418120D01*
X226205Y419527D01*
X224367Y420288D01*
X222378D01*
X220540Y419527D01*
X219134Y418120D01*
X218373Y416283D01*
Y414294D01*
X219134Y412456D01*
X220540Y411049D01*
X222378Y410288D01*
X224367D01*
X226205Y411049D01*
X227611Y412456D01*
X227724Y412729D01*
X234788D01*
X235767Y412924D01*
X236598Y413478D01*
X239560Y416441D01*
X257666D01*
X258011Y415219D01*
X257546Y414934D01*
X253925Y411841D01*
X253838Y411783D01*
X237938Y395883D01*
X237792Y395665D01*
X234983Y393359D01*
X231549Y391524D01*
X227824Y390394D01*
X224207Y390038D01*
X223950Y390089D01*
X189947D01*
Y402971D01*
X145947D01*
Y365971D01*
X189947D01*
Y378853D01*
X223950D01*
X224053Y378873D01*
X228800Y379247D01*
X233531Y380383D01*
X238026Y382245D01*
X242174Y384787D01*
X245796Y387880D01*
X245883Y387938D01*
X261783Y403838D01*
X261929Y404056D01*
X264738Y406362D01*
X268171Y408197D01*
X271897Y409327D01*
X275513Y409683D01*
X275771Y409632D01*
X358154D01*
X358429Y409687D01*
X361409Y409980D01*
X364539Y410930D01*
X367424Y412472D01*
X369739Y414372D01*
X369972Y414528D01*
X370033Y414588D01*
X370179Y414806D01*
X372988Y417112D01*
X376422Y418947D01*
X380147Y420077D01*
X383764Y420433D01*
X384021Y420382D01*
X427153D01*
X427256Y420403D01*
X432003Y420776D01*
X436734Y421912D01*
X441229Y423774D01*
X445377Y426316D01*
X446912Y427626D01*
X448900D01*
Y417687D01*
X389572D01*
X389546Y417682D01*
X385306Y417264D01*
X381204Y416020D01*
X377424Y413999D01*
X374110Y411280D01*
X371390Y407966D01*
X369370Y404186D01*
X368125Y400084D01*
X367705Y395817D01*
X367709Y395782D01*
X367753Y394531D01*
X367745Y393264D01*
X367403Y388915D01*
X366088Y383437D01*
X363932Y378232D01*
X360989Y373429D01*
X357547Y369400D01*
X357269Y369213D01*
X353660Y365605D01*
X352390Y366131D01*
Y367900D01*
X348750D01*
Y364360D01*
X350619D01*
X351145Y363090D01*
X319190Y331135D01*
X316896Y331750D01*
X313605D01*
X310425Y330898D01*
X307575Y329253D01*
X305248Y326925D01*
X303602Y324075D01*
X302750Y320896D01*
Y317604D01*
X303365Y315310D01*
X302203Y314148D01*
X300073Y316278D01*
X288972Y305177D01*
X282183Y298389D01*
X283064Y297509D01*
X276819Y291264D01*
X275900Y291385D01*
X271100D01*
X268855Y291090D01*
X266763Y290223D01*
X264967Y288845D01*
X263893Y287446D01*
X263085Y287986D01*
X260900Y288421D01*
X256100D01*
X253915Y287986D01*
X252063Y286748D01*
X251635Y286108D01*
X250365D01*
X249937Y286748D01*
X248506Y287705D01*
X248215Y288969D01*
X248252Y289248D01*
X248483Y289479D01*
X249245Y291316D01*
Y293305D01*
X248483Y295143D01*
X247077Y296550D01*
X245239Y297311D01*
X243250D01*
X241412Y296550D01*
X240006Y295143D01*
X239245Y293305D01*
Y291316D01*
X240006Y289479D01*
X239572Y288117D01*
X238915Y287986D01*
X237063Y286748D01*
X236635Y286108D01*
X235365D01*
X234937Y286748D01*
X233085Y287986D01*
X230900Y288421D01*
X226100D01*
X223915Y287986D01*
X222063Y286748D01*
X221635Y286108D01*
X220365D01*
X219937Y286748D01*
X218338Y287817D01*
Y289921D01*
X220700D01*
Y295561D01*
X222700D01*
Y297561D01*
X228240D01*
Y301201D01*
X229377Y301521D01*
X236790D01*
Y307061D01*
X222210D01*
Y301708D01*
X221252Y301415D01*
X220250Y302232D01*
Y316061D01*
X218338D01*
Y326181D01*
X218630Y327648D01*
Y329902D01*
X223268Y334541D01*
X223801Y334761D01*
X225207Y336168D01*
X225968Y338005D01*
Y339995D01*
X225207Y341832D01*
X223801Y343239D01*
X221963Y344000D01*
X219974D01*
X218136Y343239D01*
X216730Y341832D01*
X216126Y340376D01*
X210798Y335047D01*
X209803Y333559D01*
X209454Y331803D01*
Y328823D01*
X209162Y327356D01*
Y316061D01*
X206750D01*
Y302061D01*
X209162D01*
Y300661D01*
X208500D01*
Y290461D01*
X209162D01*
Y288035D01*
X208915Y287986D01*
X207063Y286748D01*
X205825Y284896D01*
X205390Y282711D01*
Y266911D01*
X205825Y264726D01*
X207063Y262874D01*
X208915Y261636D01*
X211100Y261201D01*
X215900D01*
X218085Y261636D01*
X219937Y262874D01*
X220365Y263514D01*
X221635D01*
X222063Y262874D01*
X223915Y261636D01*
X226100Y261201D01*
X230900D01*
X233085Y261636D01*
X234937Y262874D01*
X235365Y263514D01*
X236635D01*
X237063Y262874D01*
X238791Y261719D01*
X238985Y261384D01*
X239224Y260526D01*
X239215Y260281D01*
X238500Y258556D01*
Y256566D01*
X239261Y254729D01*
X240668Y253322D01*
X242505Y252561D01*
X244495D01*
X246332Y253322D01*
X247739Y254729D01*
X248500Y256566D01*
Y258556D01*
X247785Y260281D01*
X247776Y260526D01*
X248015Y261384D01*
X248209Y261719D01*
X249937Y262874D01*
X250365Y263514D01*
X251635D01*
X252063Y262874D01*
X253915Y261636D01*
X256100Y261201D01*
X260900D01*
X263085Y261636D01*
X263893Y262176D01*
X264967Y260777D01*
X266763Y259399D01*
X268855Y258532D01*
X271100Y258237D01*
X275900D01*
X278145Y258532D01*
X280237Y259399D01*
X282034Y260777D01*
X283412Y262574D01*
X284279Y264666D01*
X284574Y266911D01*
Y282711D01*
X284526Y283081D01*
X291008Y289564D01*
X293639Y286933D01*
X300427Y293722D01*
X311528Y304823D01*
X310148Y306203D01*
X311310Y307365D01*
X313605Y306750D01*
X316896D01*
X320075Y307602D01*
X322925Y309248D01*
X325253Y311575D01*
X326898Y314425D01*
X327750Y317604D01*
Y320896D01*
X327135Y323190D01*
X365214Y361269D01*
X365246Y361316D01*
X369262Y365896D01*
X372680Y371012D01*
X375402Y376530D01*
X377379Y382357D01*
X378580Y388391D01*
X378979Y394476D01*
X378989Y394531D01*
X378977Y394976D01*
X378866Y395817D01*
X379231Y398588D01*
X380300Y401171D01*
X382002Y403388D01*
X384219Y405089D01*
X386801Y406159D01*
X389353Y406495D01*
X389572Y406451D01*
X448900D01*
Y404226D01*
X465100D01*
Y413826D01*
Y428627D01*
X480849D01*
Y430480D01*
X481233Y430531D01*
X484205Y431762D01*
X486757Y433720D01*
X488715Y436272D01*
X489946Y439243D01*
X490360Y442394D01*
X490368Y442432D01*
Y465068D01*
X490373D01*
X489921Y469665D01*
X488580Y474086D01*
X486402Y478161D01*
X483471Y481732D01*
X483467Y481728D01*
X480723Y484473D01*
X480594Y484558D01*
X477793Y486857D01*
X474464Y488637D01*
X470850Y489733D01*
X467245Y490088D01*
X467093Y490118D01*
D02*
G37*
G36*
X269250Y446300D02*
X263710D01*
Y441010D01*
X269250D01*
Y446300D01*
D02*
G37*
G36*
X367540Y445390D02*
X360750D01*
Y440600D01*
X367540D01*
Y445390D01*
D02*
G37*
G36*
X356750D02*
X349960D01*
Y440600D01*
X356750D01*
Y445390D01*
D02*
G37*
G36*
X367540Y436600D02*
X360750D01*
Y431810D01*
X367540D01*
Y436600D01*
D02*
G37*
G36*
X356750D02*
X349960D01*
Y431810D01*
X356750D01*
Y436600D01*
D02*
G37*
G36*
X347950Y440800D02*
X337450D01*
Y424300D01*
X347950D01*
Y440800D01*
D02*
G37*
G36*
X97019Y457500D02*
X92981D01*
X89020Y456712D01*
X85289Y455167D01*
X81932Y452923D01*
X79077Y450068D01*
X76833Y446710D01*
X75288Y442980D01*
X74500Y439019D01*
Y434981D01*
X75288Y431020D01*
X76833Y427290D01*
X79077Y423932D01*
X81932Y421077D01*
X85289Y418833D01*
X89020Y417288D01*
X92981Y416500D01*
X97019D01*
X100980Y417288D01*
X104710Y418833D01*
X108068Y421077D01*
X110923Y423932D01*
X113167Y427290D01*
X114712Y431020D01*
X115500Y434981D01*
Y439019D01*
X114712Y442980D01*
X113167Y446710D01*
X110923Y450068D01*
X108068Y452923D01*
X104710Y455167D01*
X100980Y456712D01*
X97019Y457500D01*
D02*
G37*
G36*
X18780Y402960D02*
X16791D01*
X14953Y402199D01*
X13547Y400792D01*
X12785Y398955D01*
Y396965D01*
X13547Y395128D01*
X14953Y393721D01*
X16791Y392960D01*
X18780D01*
X20618Y393721D01*
X22024Y395128D01*
X22785Y396965D01*
Y398955D01*
X22024Y400792D01*
X20618Y402199D01*
X18780Y402960D01*
D02*
G37*
G36*
X346264Y398919D02*
X344275D01*
X342437Y398158D01*
X341031Y396751D01*
X340269Y394914D01*
Y392924D01*
X341031Y391087D01*
X342437Y389680D01*
X344275Y388919D01*
X346264D01*
X348102Y389680D01*
X349508Y391087D01*
X350269Y392924D01*
Y394914D01*
X349508Y396751D01*
X348102Y398158D01*
X346264Y398919D01*
D02*
G37*
G36*
X420947Y399971D02*
X382947D01*
Y368971D01*
X386949D01*
Y364257D01*
X386789Y364096D01*
X386028Y362258D01*
Y360269D01*
X386789Y358432D01*
X388195Y357025D01*
X390033Y356264D01*
X392022D01*
X393860Y357025D01*
X395266Y358432D01*
X396028Y360269D01*
Y362258D01*
X395266Y364096D01*
X395106Y364257D01*
Y368971D01*
X420947D01*
Y380071D01*
X425527D01*
Y376950D01*
X431167D01*
X436807D01*
Y380490D01*
X436267D01*
Y389149D01*
X426067D01*
Y388228D01*
X420947D01*
Y399971D01*
D02*
G37*
G36*
X316245Y397363D02*
X314256D01*
X312418Y396602D01*
X311011Y395196D01*
X310250Y393358D01*
Y391369D01*
X310662Y390374D01*
Y387570D01*
X309417Y386851D01*
X307648Y385083D01*
X306397Y382916D01*
X305750Y380500D01*
Y377999D01*
X306397Y375583D01*
X307648Y373416D01*
X309417Y371648D01*
X311583Y370397D01*
X313999Y369749D01*
X316501D01*
X318917Y370397D01*
X321083Y371648D01*
X322852Y373416D01*
X323484Y374512D01*
X341110D01*
Y371900D01*
X346750D01*
X352390D01*
Y375440D01*
X351850D01*
Y384100D01*
X341650D01*
Y383688D01*
X323657D01*
X322852Y385083D01*
X321083Y386851D01*
X319838Y387570D01*
Y390374D01*
X320250Y391369D01*
Y393358D01*
X319489Y395196D01*
X318082Y396602D01*
X316245Y397363D01*
D02*
G37*
G36*
X284001Y388749D02*
X281499D01*
X279083Y388102D01*
X276917Y386851D01*
X275148Y385083D01*
X273897Y382916D01*
X273250Y380500D01*
Y377999D01*
X273897Y375583D01*
X275148Y373416D01*
X276917Y371648D01*
X279083Y370397D01*
X281499Y369749D01*
X284001D01*
X286417Y370397D01*
X288583Y371648D01*
X290352Y373416D01*
X291603Y375583D01*
X292250Y377999D01*
Y380500D01*
X291603Y382916D01*
X290352Y385083D01*
X288583Y386851D01*
X286417Y388102D01*
X284001Y388749D01*
D02*
G37*
G36*
X436807Y372949D02*
X433167D01*
Y369409D01*
X436807D01*
Y372949D01*
D02*
G37*
G36*
X429167D02*
X425527D01*
Y369409D01*
X429167D01*
Y372949D01*
D02*
G37*
G36*
X344750Y367900D02*
X341110D01*
Y364360D01*
X344750D01*
Y367900D01*
D02*
G37*
G36*
X18495Y372710D02*
X16505D01*
X14668Y371949D01*
X13261Y370542D01*
X12500Y368704D01*
Y366715D01*
X13261Y364878D01*
X14668Y363471D01*
X15148Y363272D01*
Y361898D01*
X14668Y361699D01*
X13261Y360292D01*
X12500Y358455D01*
Y356465D01*
X13261Y354628D01*
X14668Y353221D01*
X16505Y352460D01*
X18495D01*
X20332Y353221D01*
X21739Y354628D01*
X22500Y356465D01*
Y358455D01*
X21739Y360292D01*
X20332Y361699D01*
X19852Y361898D01*
Y363272D01*
X20332Y363471D01*
X21739Y364878D01*
X22500Y366715D01*
Y368704D01*
X21739Y370542D01*
X20332Y371949D01*
X18495Y372710D01*
D02*
G37*
G36*
X96604Y358378D02*
X94615D01*
X92777Y357617D01*
X91371Y356210D01*
X90610Y354372D01*
Y352383D01*
X91371Y350546D01*
X92777Y349139D01*
X94615Y348378D01*
X96604D01*
X98442Y349139D01*
X99848Y350546D01*
X100610Y352383D01*
Y354372D01*
X99848Y356210D01*
X98442Y357617D01*
X96604Y358378D01*
D02*
G37*
G36*
X355745Y344500D02*
X353755D01*
X351918Y343739D01*
X350511Y342332D01*
X349750Y340495D01*
Y338505D01*
X350511Y336668D01*
X351918Y335261D01*
X353755Y334500D01*
X355745D01*
X357582Y335261D01*
X358989Y336668D01*
X359750Y338505D01*
Y340495D01*
X358989Y342332D01*
X357582Y343739D01*
X355745Y344500D01*
D02*
G37*
G36*
X357250Y329108D02*
Y321250D01*
X365108D01*
X364606Y323125D01*
X363284Y325415D01*
X361415Y327284D01*
X359125Y328606D01*
X357250Y329108D01*
D02*
G37*
G36*
X353250Y329108D02*
X351375Y328606D01*
X349085Y327284D01*
X347216Y325415D01*
X345894Y323125D01*
X345392Y321250D01*
X353250D01*
Y329108D01*
D02*
G37*
G36*
X284750Y329108D02*
Y321250D01*
X292609D01*
X292106Y323125D01*
X290784Y325415D01*
X288915Y327284D01*
X286625Y328606D01*
X284750Y329108D01*
D02*
G37*
G36*
X280750Y329108D02*
X278875Y328606D01*
X276586Y327284D01*
X274716Y325415D01*
X273394Y323125D01*
X272892Y321250D01*
X280750D01*
Y329108D01*
D02*
G37*
G36*
X467243Y377500D02*
X462757D01*
X458326Y376798D01*
X454060Y375412D01*
X450063Y373375D01*
X446433Y370739D01*
X443261Y367566D01*
X440625Y363937D01*
X438588Y359940D01*
X437202Y355674D01*
X436500Y351243D01*
Y346757D01*
X437202Y342326D01*
X438588Y338060D01*
X440625Y334063D01*
X443261Y330434D01*
X446433Y327261D01*
X450063Y324625D01*
X454060Y322588D01*
X458326Y321202D01*
X462757Y320500D01*
X467243D01*
X471674Y321202D01*
X475940Y322588D01*
X479937Y324625D01*
X483567Y327261D01*
X486739Y330434D01*
X489375Y334063D01*
X491412Y338060D01*
X492798Y342326D01*
X493500Y346757D01*
Y351243D01*
X492798Y355674D01*
X491412Y359940D01*
X489375Y363937D01*
X486739Y367566D01*
X483567Y370739D01*
X479937Y373375D01*
X475940Y375412D01*
X471674Y376798D01*
X467243Y377500D01*
D02*
G37*
G36*
X236790Y316601D02*
X231500D01*
Y311061D01*
X236790D01*
Y316601D01*
D02*
G37*
G36*
X227500D02*
X222210D01*
Y311061D01*
X227500D01*
Y316601D01*
D02*
G37*
G36*
X365108Y317250D02*
X357250D01*
Y309392D01*
X359125Y309894D01*
X361415Y311216D01*
X363284Y313085D01*
X364606Y315375D01*
X365108Y317250D01*
D02*
G37*
G36*
X353250D02*
X345392D01*
X345894Y315375D01*
X347216Y313085D01*
X349085Y311216D01*
X351375Y309894D01*
X353250Y309392D01*
Y317250D01*
D02*
G37*
G36*
X280750Y317250D02*
X272892D01*
X273394Y315375D01*
X274716Y313085D01*
X276586Y311216D01*
X278875Y309894D01*
X280750Y309391D01*
Y317250D01*
D02*
G37*
G36*
X292609D02*
X284750D01*
Y309391D01*
X286625Y309894D01*
X288915Y311216D01*
X290784Y313085D01*
X292106Y315375D01*
X292609Y317250D01*
D02*
G37*
G36*
X228240Y293561D02*
X224700D01*
Y289921D01*
X228240D01*
Y293561D01*
D02*
G37*
G36*
X423947Y313971D02*
X379947D01*
Y276971D01*
X394356D01*
X395129Y275963D01*
X395000Y275484D01*
Y273377D01*
X395545Y271343D01*
X396599Y269518D01*
X398088Y268029D01*
X399912Y266976D01*
X401947Y266430D01*
X404053D01*
X406088Y266976D01*
X407912Y268029D01*
X409402Y269518D01*
X410455Y271343D01*
X411000Y273377D01*
Y275484D01*
X410872Y275963D01*
X411645Y276971D01*
X423947D01*
Y313971D01*
D02*
G37*
G36*
X459000Y266912D02*
Y256000D01*
X469912D01*
X469105Y259014D01*
X467395Y261976D01*
X464976Y264395D01*
X462014Y266105D01*
X459000Y266912D01*
D02*
G37*
G36*
X455000Y266912D02*
X451986Y266105D01*
X449024Y264395D01*
X446605Y261976D01*
X444895Y259014D01*
X444088Y256000D01*
X455000D01*
Y266912D01*
D02*
G37*
G36*
X356501Y268750D02*
X353999D01*
X351583Y268103D01*
X349417Y266852D01*
X347648Y265083D01*
X346398Y262917D01*
X345750Y260501D01*
Y257999D01*
X346398Y255583D01*
X347648Y253417D01*
X349417Y251648D01*
X351583Y250397D01*
X353999Y249750D01*
X356501D01*
X358917Y250397D01*
X361083Y251648D01*
X362852Y253417D01*
X364103Y255583D01*
X364750Y257999D01*
Y260501D01*
X364103Y262917D01*
X362852Y265083D01*
X361083Y266852D01*
X358917Y268103D01*
X356501Y268750D01*
D02*
G37*
G36*
X43210Y247790D02*
X42164Y247250D01*
X40947Y247250D01*
X40750Y247289D01*
X27750D01*
X27553Y247250D01*
X25750D01*
Y245447D01*
X25711Y245250D01*
X25711Y199133D01*
X24313Y197735D01*
X24312Y197735D01*
X23870Y197073D01*
X23715Y196293D01*
Y191100D01*
X22150D01*
Y166900D01*
X23715D01*
Y163372D01*
X14842Y154499D01*
X14400Y153837D01*
X14245Y153057D01*
X14245Y125432D01*
X14400Y124652D01*
X14842Y123990D01*
X18464Y120368D01*
X18471Y120363D01*
X18477Y120356D01*
X18802Y120142D01*
X19125Y119926D01*
X19134Y119924D01*
X19142Y119920D01*
X19524Y119847D01*
X19906Y119771D01*
X19915Y119773D01*
X19924Y119771D01*
X34259Y119896D01*
X49698D01*
X50478Y120051D01*
X51140Y120493D01*
X51140Y120494D01*
X53692Y123046D01*
X54134Y123707D01*
X54289Y124487D01*
X54289Y152447D01*
X54289Y152448D01*
X54134Y153228D01*
X53692Y153890D01*
X53692Y153890D01*
X43955Y163627D01*
Y166900D01*
X46350D01*
Y174892D01*
X47620Y175059D01*
X47871Y174121D01*
X49535Y171239D01*
X51889Y168885D01*
X54771Y167221D01*
X57650Y166450D01*
Y179000D01*
Y191550D01*
X54771Y190779D01*
X51889Y189114D01*
X49535Y186761D01*
X47871Y183879D01*
X47620Y182941D01*
X46350Y183108D01*
Y191100D01*
X43955D01*
Y196863D01*
X43955Y196863D01*
X43800Y197643D01*
X43358Y198305D01*
X43358Y198305D01*
X42789Y198873D01*
Y199864D01*
X43210Y200960D01*
X44059Y200960D01*
X50250D01*
Y211750D01*
Y222540D01*
X44059D01*
X43210Y222540D01*
X42789Y223636D01*
Y225114D01*
X43210Y226210D01*
X44059Y226210D01*
X50250D01*
Y237000D01*
Y247790D01*
X43382Y247790D01*
X43210D01*
D02*
G37*
G36*
X469912Y252000D02*
X459000D01*
Y241088D01*
X462014Y241895D01*
X464976Y243605D01*
X467395Y246024D01*
X469105Y248986D01*
X469912Y252000D01*
D02*
G37*
G36*
X455000D02*
X444088D01*
X444895Y248986D01*
X446605Y246024D01*
X449024Y243605D01*
X451986Y241895D01*
X455000Y241088D01*
Y252000D01*
D02*
G37*
G36*
X54250Y247790D02*
Y239000D01*
X61290D01*
Y247790D01*
X54250D01*
D02*
G37*
G36*
X329966Y237703D02*
X326426D01*
Y234063D01*
X329966D01*
Y237703D01*
D02*
G37*
G36*
X275900Y240971D02*
X275500D01*
Y228811D01*
X282160D01*
Y234711D01*
X281684Y237107D01*
X280327Y239138D01*
X278296Y240495D01*
X275900Y240971D01*
D02*
G37*
G36*
X61290Y235000D02*
X54250D01*
Y226210D01*
X61290D01*
Y235000D01*
D02*
G37*
G36*
X316500Y268750D02*
X313999D01*
X311583Y268103D01*
X309417Y266852D01*
X307648Y265083D01*
X306397Y262917D01*
X305750Y260501D01*
Y257999D01*
X306397Y255583D01*
X307648Y253417D01*
X309417Y251648D01*
X310574Y250980D01*
Y237163D01*
X310226D01*
Y226963D01*
X310226Y226963D01*
X310226D01*
X310226Y226963D01*
X309940Y225811D01*
X308250D01*
Y211811D01*
X310574D01*
Y205691D01*
X310569Y205679D01*
X310290Y205262D01*
X310192Y204769D01*
X310000Y204306D01*
Y203804D01*
X309902Y203311D01*
X310000Y202819D01*
Y202316D01*
X310192Y201853D01*
X310290Y201360D01*
X310569Y200943D01*
X310761Y200479D01*
X311116Y200124D01*
X311395Y199706D01*
X311813Y199427D01*
X312168Y199072D01*
X312632Y198880D01*
X313049Y198601D01*
X313542Y198503D01*
X314006Y198311D01*
X314508D01*
X315000Y198213D01*
X315493Y198311D01*
X315995D01*
X316458Y198503D01*
X316951Y198601D01*
X317368Y198880D01*
X317832Y199072D01*
X318187Y199427D01*
X318605Y199706D01*
X318767Y199868D01*
X319046Y200286D01*
X319239Y200479D01*
X319343Y200731D01*
X319872Y201522D01*
X320260Y203473D01*
X319872Y205424D01*
X319750Y205606D01*
Y211811D01*
X321750D01*
Y225294D01*
X322862Y226066D01*
X323710Y225745D01*
Y220811D01*
X338290D01*
Y226351D01*
X331206D01*
X329966Y226423D01*
X329966Y227621D01*
Y230063D01*
X324426D01*
Y232063D01*
X322425D01*
Y237703D01*
X319750D01*
Y250879D01*
X321083Y251648D01*
X322852Y253417D01*
X324102Y255583D01*
X324750Y257999D01*
Y260501D01*
X324102Y262917D01*
X322852Y265083D01*
X321083Y266852D01*
X318917Y268103D01*
X316500Y268750D01*
D02*
G37*
G36*
X54250Y222540D02*
Y213750D01*
X61290D01*
Y222540D01*
X54250D01*
D02*
G37*
G36*
X282160Y224811D02*
X275500D01*
Y212651D01*
X275900D01*
X278296Y213127D01*
X280327Y214484D01*
X281684Y216515D01*
X282160Y218911D01*
Y224811D01*
D02*
G37*
G36*
X215900Y245421D02*
X211100D01*
X208915Y244986D01*
X207063Y243748D01*
X205825Y241896D01*
X205390Y239711D01*
Y218911D01*
X205825Y216726D01*
X207063Y214874D01*
X208915Y213636D01*
X209422Y213535D01*
Y201872D01*
X208650D01*
Y191672D01*
X218565D01*
X219414Y190402D01*
X219129Y189715D01*
Y187726D01*
X219890Y185889D01*
X221297Y184482D01*
X223134Y183721D01*
X225124D01*
X226961Y184482D01*
X228368Y185889D01*
X229129Y187726D01*
Y189715D01*
X228368Y191553D01*
X227950Y191971D01*
Y201872D01*
X217578D01*
Y213535D01*
X218085Y213636D01*
X219937Y214874D01*
X220365Y215514D01*
X221635D01*
X222063Y214874D01*
X223696Y213782D01*
X223982Y213076D01*
X224074Y212309D01*
X223424Y210738D01*
Y208749D01*
X224185Y206912D01*
X225591Y205505D01*
X227429Y204744D01*
X229418D01*
X231256Y205505D01*
X232662Y206912D01*
X233424Y208749D01*
Y210738D01*
X232777Y212299D01*
X233028Y213388D01*
X233163Y213688D01*
X234937Y214874D01*
X235365Y215514D01*
X236635D01*
X237063Y214874D01*
X238915Y213636D01*
X239070Y213605D01*
X239550Y212215D01*
X238939Y210738D01*
Y208749D01*
X239700Y206912D01*
X241106Y205505D01*
X242944Y204744D01*
X244933D01*
X246771Y205505D01*
X248178Y206912D01*
X248939Y208749D01*
Y210738D01*
X248260Y212376D01*
X248215Y212704D01*
X248582Y213968D01*
X249937Y214874D01*
X250365Y215514D01*
X251635D01*
X252063Y214874D01*
X253915Y213636D01*
X254070Y213605D01*
X254550Y212215D01*
X253939Y210738D01*
Y208749D01*
X254700Y206912D01*
X256106Y205505D01*
X257944Y204744D01*
X259933D01*
X261771Y205505D01*
X263178Y206912D01*
X263939Y208749D01*
Y210738D01*
X263260Y212376D01*
X263215Y212704D01*
X263582Y213968D01*
X264902Y214850D01*
X265221Y215028D01*
X266310D01*
X266673Y214484D01*
X268704Y213127D01*
X271100Y212651D01*
X271500D01*
Y226811D01*
Y240971D01*
X271100D01*
X268704Y240495D01*
X266673Y239138D01*
X266310Y238594D01*
X265221D01*
X264902Y238772D01*
X263085Y239986D01*
X260900Y240421D01*
X256100D01*
X253915Y239986D01*
X252063Y238748D01*
X251635Y238108D01*
X250365D01*
X249937Y238748D01*
X248085Y239986D01*
X245900Y240421D01*
X241100D01*
X238915Y239986D01*
X237063Y238748D01*
X236635Y238108D01*
X235365D01*
X234937Y238748D01*
X233085Y239986D01*
X230900Y240421D01*
X226100D01*
X223915Y239986D01*
X222880Y239294D01*
X222184Y239523D01*
X221564Y239942D01*
X221175Y241896D01*
X219937Y243748D01*
X218085Y244986D01*
X215900Y245421D01*
D02*
G37*
G36*
X338290Y216811D02*
X333000D01*
Y211271D01*
X338290D01*
Y216811D01*
D02*
G37*
G36*
X329000D02*
X323710D01*
Y211271D01*
X329000D01*
Y216811D01*
D02*
G37*
G36*
X187487Y222511D02*
X169947D01*
Y208471D01*
X187487D01*
Y222511D01*
D02*
G37*
G36*
X165947D02*
X148407D01*
Y208471D01*
X165947D01*
Y222511D01*
D02*
G37*
G36*
X61290Y209750D02*
X54250D01*
Y200960D01*
X61290D01*
Y209750D01*
D02*
G37*
G36*
X187487Y204471D02*
X169947D01*
Y190431D01*
X187487D01*
Y204471D01*
D02*
G37*
G36*
X165947D02*
X148407D01*
Y190431D01*
X165947D01*
Y204471D01*
D02*
G37*
G36*
X280201Y195705D02*
X278212D01*
X276374Y194944D01*
X274967Y193537D01*
X274206Y191700D01*
Y189711D01*
X274967Y187873D01*
X276374Y186466D01*
X278212Y185705D01*
X280201D01*
X282038Y186466D01*
X283445Y187873D01*
X284206Y189711D01*
Y191700D01*
X283445Y193537D01*
X282038Y194944D01*
X280201Y195705D01*
D02*
G37*
G36*
X61650Y191550D02*
Y181000D01*
X72200D01*
X71429Y183879D01*
X69764Y186761D01*
X67411Y189114D01*
X64529Y190779D01*
X61650Y191550D01*
D02*
G37*
G36*
X423947Y224971D02*
X379947D01*
Y187971D01*
X394446D01*
X395220Y186963D01*
X395000Y186144D01*
Y184037D01*
X395545Y182003D01*
X396599Y180179D01*
X398088Y178689D01*
X399912Y177636D01*
X401947Y177091D01*
X404053D01*
X406088Y177636D01*
X407912Y178689D01*
X409402Y180179D01*
X410455Y182003D01*
X411000Y184037D01*
Y186144D01*
X410780Y186963D01*
X411554Y187971D01*
X423947D01*
Y224971D01*
D02*
G37*
G36*
X212995Y179955D02*
X211005D01*
X209168Y179194D01*
X207761Y177787D01*
X207000Y175950D01*
Y173960D01*
X207761Y172123D01*
X209168Y170716D01*
X211005Y169955D01*
X212995D01*
X214832Y170716D01*
X216239Y172123D01*
X217000Y173960D01*
Y175950D01*
X216239Y177787D01*
X214832Y179194D01*
X212995Y179955D01*
D02*
G37*
G36*
X72200Y177000D02*
X61650D01*
Y166450D01*
X64529Y167221D01*
X67411Y168885D01*
X69764Y171239D01*
X71429Y174121D01*
X72200Y177000D01*
D02*
G37*
G36*
X123190Y158990D02*
X111500D01*
Y149450D01*
X123190D01*
Y158990D01*
D02*
G37*
G36*
X85690D02*
X74000D01*
Y149450D01*
X85690D01*
Y158990D01*
D02*
G37*
G36*
X107500D02*
X95810D01*
Y149450D01*
X107500D01*
Y158990D01*
D02*
G37*
G36*
X70000D02*
X58310D01*
Y149450D01*
X70000D01*
Y158990D01*
D02*
G37*
G36*
X123190Y145450D02*
X111500D01*
Y135910D01*
X123190D01*
Y145450D01*
D02*
G37*
G36*
X107500D02*
X95810D01*
Y135910D01*
X107500D01*
Y145450D01*
D02*
G37*
G36*
X85690D02*
X74000D01*
Y135910D01*
X85690D01*
Y145450D01*
D02*
G37*
G36*
X70000D02*
X58310D01*
Y135910D01*
X70000D01*
Y145450D01*
D02*
G37*
G36*
X245984Y117279D02*
X232693D01*
Y111489D01*
X245984D01*
Y117279D01*
D02*
G37*
G36*
X228693D02*
X215403D01*
Y111489D01*
X228693D01*
Y117279D01*
D02*
G37*
G36*
X467243Y166500D02*
X462757D01*
X458326Y165798D01*
X454060Y164412D01*
X450063Y162375D01*
X446433Y159739D01*
X443261Y156566D01*
X440625Y152937D01*
X438588Y148940D01*
X437202Y144674D01*
X436500Y140243D01*
Y135757D01*
X437202Y131326D01*
X438588Y127060D01*
X440625Y123063D01*
X443261Y119433D01*
X446433Y116261D01*
X450063Y113625D01*
X454060Y111588D01*
X458326Y110202D01*
X462757Y109500D01*
X467243D01*
X471674Y110202D01*
X475940Y111588D01*
X479937Y113625D01*
X483567Y116261D01*
X486739Y119433D01*
X489375Y123063D01*
X491412Y127060D01*
X492798Y131326D01*
X493500Y135757D01*
Y140243D01*
X492798Y144674D01*
X491412Y148940D01*
X489375Y152937D01*
X486739Y156566D01*
X483567Y159739D01*
X479937Y162375D01*
X475940Y164412D01*
X471674Y165798D01*
X467243Y166500D01*
D02*
G37*
G36*
X245984Y107489D02*
X232693D01*
Y101699D01*
X245984D01*
Y107489D01*
D02*
G37*
G36*
X228693D02*
X215403D01*
Y101699D01*
X228693D01*
Y107489D01*
D02*
G37*
G36*
X157900Y130650D02*
X131600D01*
Y130039D01*
X59328D01*
X58548Y129884D01*
X57886Y129442D01*
X57444Y128780D01*
X57289Y128000D01*
Y114039D01*
X18058D01*
X17278Y113884D01*
X16616Y113442D01*
X16174Y112780D01*
X16019Y112000D01*
Y76839D01*
X16174Y76059D01*
X16616Y75397D01*
X17278Y74955D01*
X17493Y74912D01*
X17461Y74750D01*
Y19500D01*
X17616Y18720D01*
X18058Y18058D01*
X18720Y17616D01*
X19500Y17461D01*
X157250D01*
X158030Y17616D01*
X158692Y18058D01*
X159134Y18720D01*
X159289Y19500D01*
Y44211D01*
X163110D01*
Y37150D01*
X166750D01*
Y42690D01*
X170750D01*
Y37150D01*
X174390D01*
Y44211D01*
X181460D01*
Y40250D01*
X192250D01*
X203040D01*
Y44211D01*
X246250D01*
X247030Y44366D01*
X247692Y44808D01*
X248134Y45470D01*
X248289Y46250D01*
Y49739D01*
X248244Y49966D01*
X248237Y50196D01*
X247971Y51356D01*
X247901Y51512D01*
X247867Y51679D01*
X247739Y51871D01*
X247645Y52082D01*
X247520Y52199D01*
X247425Y52341D01*
X247234Y52469D01*
X247066Y52627D01*
X246906Y52688D01*
X246764Y52783D01*
X246538Y52828D01*
X246322Y52910D01*
X245443Y53873D01*
Y63505D01*
X246322Y64468D01*
X246538Y64550D01*
X246764Y64595D01*
X246906Y64690D01*
X247066Y64751D01*
X247234Y64909D01*
X247425Y65037D01*
X247520Y65179D01*
X247645Y65296D01*
X247739Y65507D01*
X247867Y65699D01*
X247901Y65866D01*
X247971Y66022D01*
X248237Y67182D01*
X248244Y67412D01*
X248289Y67639D01*
Y74750D01*
X248134Y75530D01*
X247692Y76192D01*
X247030Y76634D01*
X246250Y76789D01*
X246249Y76789D01*
X245443Y76839D01*
Y90364D01*
X245553Y90437D01*
X245996Y91099D01*
X246151Y91879D01*
Y97000D01*
X245996Y97780D01*
X245553Y98442D01*
X244892Y98884D01*
X244112Y99039D01*
X166289D01*
Y100893D01*
X166200Y101342D01*
Y102864D01*
X166289Y103313D01*
Y128000D01*
X166134Y128780D01*
X165692Y129442D01*
X165030Y129884D01*
X164250Y130039D01*
X160107D01*
X159353Y129889D01*
X158147D01*
X157900Y129938D01*
Y130650D01*
D02*
G37*
G36*
X458639Y63450D02*
X455361D01*
X452195Y62602D01*
X449356Y60963D01*
X447038Y58644D01*
X445398Y55806D01*
X444550Y52639D01*
Y49361D01*
X445398Y46195D01*
X447038Y43355D01*
X449356Y41038D01*
X452195Y39398D01*
X455361Y38550D01*
X458639D01*
X461805Y39398D01*
X464645Y41038D01*
X466963Y43355D01*
X468602Y46195D01*
X469450Y49361D01*
Y52639D01*
X468602Y55806D01*
X466963Y58644D01*
X464645Y60963D01*
X461805Y62602D01*
X458639Y63450D01*
D02*
G37*
G36*
X368193Y138339D02*
X295194D01*
Y29839D01*
X368193D01*
Y138339D01*
D02*
G37*
G36*
X203040Y36250D02*
X194250D01*
Y29210D01*
X203040D01*
Y36250D01*
D02*
G37*
G36*
X190250D02*
X181460D01*
Y29210D01*
X190250D01*
Y36250D01*
D02*
G37*
G36*
X408019Y61500D02*
X403981D01*
X400020Y60712D01*
X396290Y59167D01*
X392932Y56923D01*
X390077Y54068D01*
X387833Y50710D01*
X386288Y46980D01*
X385500Y43019D01*
Y38981D01*
X386288Y35020D01*
X387833Y31290D01*
X390077Y27932D01*
X392932Y25077D01*
X396290Y22833D01*
X400020Y21288D01*
X403981Y20500D01*
X408019D01*
X411980Y21288D01*
X415710Y22833D01*
X419068Y25077D01*
X421923Y27932D01*
X424167Y31290D01*
X425712Y35020D01*
X426500Y38981D01*
Y43019D01*
X425712Y46980D01*
X424167Y50710D01*
X421923Y54068D01*
X419068Y56923D01*
X415710Y59167D01*
X411980Y60712D01*
X408019Y61500D01*
D02*
G37*
%LPD*%
G36*
X40750Y198028D02*
X41916Y196863D01*
Y162782D01*
X52250Y152448D01*
X52250Y124487D01*
X49698Y121935D01*
X34250D01*
X19906Y121810D01*
X16284Y125432D01*
X16284Y153057D01*
X25754Y162527D01*
Y196293D01*
X27750Y198288D01*
X27750Y245250D01*
X40750D01*
Y198028D01*
D02*
G37*
G36*
X164250Y103313D02*
X164161Y103098D01*
Y101109D01*
X164250Y100893D01*
Y97000D01*
X244112D01*
Y91879D01*
X232693D01*
Y84089D01*
X230693D01*
Y82089D01*
X215403D01*
Y76839D01*
X114740D01*
X114712Y76980D01*
X113167Y80710D01*
X110923Y84068D01*
X108068Y86923D01*
X104710Y89167D01*
X100980Y90712D01*
X97019Y91500D01*
X92981D01*
X89020Y90712D01*
X85289Y89167D01*
X81932Y86923D01*
X79077Y84068D01*
X76833Y80710D01*
X75288Y76980D01*
X75260Y76839D01*
X18058D01*
Y112000D01*
X59328D01*
Y128000D01*
X157393D01*
X157755Y127850D01*
X159745D01*
X160107Y128000D01*
X164250D01*
Y103313D01*
D02*
G37*
G36*
X246250Y67639D02*
X245983Y66479D01*
X244980Y66479D01*
X232693D01*
Y58689D01*
Y50899D01*
X244980D01*
X245983Y50899D01*
X246250Y49739D01*
Y46250D01*
X202500D01*
Y46750D01*
X182000D01*
Y46250D01*
X173850D01*
Y47690D01*
X163650D01*
Y46250D01*
X157250D01*
Y19500D01*
X19500D01*
Y74750D01*
X73843D01*
X74649Y73768D01*
X74500Y73019D01*
Y68981D01*
X75288Y65020D01*
X76833Y61290D01*
X79077Y57932D01*
X81932Y55077D01*
X85289Y52833D01*
X89020Y51288D01*
X92981Y50500D01*
X97019D01*
X100980Y51288D01*
X104710Y52833D01*
X108068Y55077D01*
X110923Y57932D01*
X113167Y61290D01*
X114712Y65020D01*
X115500Y68981D01*
Y73019D01*
X115351Y73768D01*
X116157Y74750D01*
X246250D01*
Y67639D01*
D02*
G37*
%LPC*%
G36*
X155540Y96290D02*
X147500D01*
Y90750D01*
X155540D01*
Y96290D01*
D02*
G37*
G36*
X143500D02*
X135460D01*
Y90750D01*
X143500D01*
Y96290D01*
D02*
G37*
G36*
X228693Y91879D02*
X215403D01*
Y86089D01*
X228693D01*
Y91879D01*
D02*
G37*
G36*
X155540Y86750D02*
X147500D01*
Y81210D01*
X155540D01*
Y86750D01*
D02*
G37*
G36*
X143500D02*
X135460D01*
Y81210D01*
X143500D01*
Y86750D01*
D02*
G37*
G36*
X228693Y66479D02*
X215403D01*
Y60689D01*
X228693D01*
Y66479D01*
D02*
G37*
G36*
X155540Y64290D02*
X147500D01*
Y58750D01*
X155540D01*
Y64290D01*
D02*
G37*
G36*
X143500D02*
X135460D01*
Y58750D01*
X143500D01*
Y64290D01*
D02*
G37*
G36*
X54000Y63644D02*
Y54000D01*
X63644D01*
X63105Y56014D01*
X61395Y58976D01*
X58976Y61395D01*
X56014Y63105D01*
X54000Y63644D01*
D02*
G37*
G36*
X48000Y63644D02*
X45986Y63105D01*
X43024Y61395D01*
X40605Y58976D01*
X38895Y56014D01*
X38356Y54000D01*
X48000D01*
Y63644D01*
D02*
G37*
G36*
X228693Y56689D02*
X215403D01*
Y50899D01*
X228693D01*
Y56689D01*
D02*
G37*
G36*
X155540Y54750D02*
X147500D01*
Y49210D01*
X155540D01*
Y54750D01*
D02*
G37*
G36*
X143500D02*
X135460D01*
Y49210D01*
X143500D01*
Y54750D01*
D02*
G37*
G36*
X48000Y48000D02*
X38356D01*
X38895Y45986D01*
X40605Y43024D01*
X43024Y40605D01*
X45986Y38895D01*
X48000Y38356D01*
Y48000D01*
D02*
G37*
G36*
X63644D02*
X54000D01*
Y38356D01*
X56014Y38895D01*
X58976Y40605D01*
X61395Y43024D01*
X63105Y45986D01*
X63644Y48000D01*
D02*
G37*
G36*
X55634Y317505D02*
X55592Y317491D01*
X55218Y317478D01*
X55176Y317464D01*
X54857Y317450D01*
X54816Y317436D01*
X54760Y317422D01*
X54580Y317408D01*
X54524Y317395D01*
X54226Y317374D01*
X54178Y317367D01*
X54136Y317381D01*
X54081Y317367D01*
X53713Y317346D01*
X53519Y317332D01*
X53436Y317318D01*
X53366Y317304D01*
X53311Y317290D01*
X53124Y317270D01*
X53068Y317256D01*
X52770Y317221D01*
X52576Y317207D01*
X52507Y317193D01*
X52451Y317180D01*
X52375Y317159D01*
X52319Y317145D01*
X52028Y317103D01*
X51848Y317089D01*
X51806Y317076D01*
X51675Y317055D01*
X51619Y317041D01*
X51501Y317006D01*
X51356Y316985D01*
X51168Y316964D01*
X50933Y316937D01*
X50856Y316916D01*
X50697Y316854D01*
X50641Y316840D01*
X50496Y316805D01*
X50420Y316770D01*
X50350Y316743D01*
X50260Y316722D01*
X50191Y316708D01*
X50024Y316680D01*
X49969Y316666D01*
X49858Y316625D01*
X49768Y316590D01*
X49629Y316576D01*
X49532Y316562D01*
X49476Y316549D01*
X49386Y316514D01*
X49317Y316486D01*
X49227Y316451D01*
X49172Y316438D01*
X49067Y316417D01*
X48998Y316389D01*
X48922Y316354D01*
X48853Y316327D01*
X48797Y316313D01*
X48651Y316278D01*
X48582Y316250D01*
X48436Y316188D01*
X48381Y316174D01*
X48277Y316153D01*
X48138Y316098D01*
X48062Y316063D01*
X47965Y316035D01*
X47847Y316015D01*
X47702Y315938D01*
X47604Y315897D01*
X47369Y315786D01*
X47272Y315772D01*
X47195Y315751D01*
X46911Y315619D01*
X46814Y315564D01*
X46661Y315494D01*
X46537Y315425D01*
X46384Y315356D01*
X46148Y315245D01*
X46017Y315224D01*
X45947Y315196D01*
X45829Y315134D01*
X45760Y315106D01*
X45302Y314870D01*
X45164Y314815D01*
X45087Y314753D01*
X45053Y314718D01*
X45025Y314704D01*
X44858Y314593D01*
X44803Y314579D01*
X44671Y314559D01*
X44595Y314510D01*
X44553Y314468D01*
X44456Y314413D01*
X44401Y314357D01*
X44373Y314343D01*
X44248Y314288D01*
X44124Y314219D01*
X43999Y314163D01*
X43929Y314122D01*
X43874Y314066D01*
X43846Y314052D01*
X43818Y314025D01*
X43791Y314011D01*
X43749Y313969D01*
X43721Y313955D01*
X43694Y313927D01*
X43638Y313914D01*
X43513Y313844D01*
X43458Y313789D01*
X43430Y313775D01*
X43389Y313733D01*
X43361Y313720D01*
X43319Y313678D01*
X43292Y313664D01*
X43222Y313636D01*
X43167Y313622D01*
X43084Y313539D01*
X43056Y313525D01*
X42931Y313428D01*
X42903Y313400D01*
X42834Y313373D01*
X42778Y313359D01*
X42702Y313297D01*
X42667Y313262D01*
X42640Y313248D01*
X42459Y313068D01*
X42432Y313054D01*
X42390Y313012D01*
X42321Y312985D01*
X42231Y312950D01*
X42196Y312915D01*
X42168Y312901D01*
X42113Y312846D01*
X42085Y312832D01*
X42043Y312790D01*
X42016Y312777D01*
X41974Y312735D01*
X41821Y312679D01*
X41738Y312596D01*
X41711Y312582D01*
X41634Y312520D01*
X41620Y312492D01*
X41558Y312430D01*
X41530Y312416D01*
X41496Y312367D01*
X41419Y312291D01*
X41392Y312277D01*
X41336Y312222D01*
X41308Y312208D01*
X41239Y312180D01*
X41149Y312146D01*
X41059Y312055D01*
X41031Y312041D01*
X40996Y312021D01*
X40982Y311993D01*
X40566Y311577D01*
X40553Y311549D01*
X40518Y311514D01*
X40490Y311501D01*
X40414Y311438D01*
X40379Y311404D01*
X40227Y311348D01*
X40171Y311293D01*
X40143Y311279D01*
X40116Y311251D01*
X40088Y311237D01*
X40040Y311189D01*
X40026Y311161D01*
X39977Y311112D01*
X39949Y311098D01*
X39901Y311050D01*
X39887Y311022D01*
X39852Y310987D01*
X39825Y310974D01*
X39762Y310911D01*
X39748Y310884D01*
X39714Y310849D01*
X39686Y310835D01*
X39637Y310786D01*
X39623Y310759D01*
X39589Y310724D01*
X39561Y310710D01*
X39499Y310648D01*
X39485Y310620D01*
X39450Y310585D01*
X39422Y310571D01*
X39374Y310523D01*
X39360Y310495D01*
X39325Y310460D01*
X39297Y310447D01*
X39235Y310384D01*
X39221Y310357D01*
X39187Y310322D01*
X39159Y310308D01*
X39096Y310246D01*
X39083Y310218D01*
X39055Y310190D01*
X39041Y310162D01*
X38999Y310121D01*
X38951Y309989D01*
X38916Y309940D01*
X38861Y309885D01*
X38847Y309857D01*
X38812Y309809D01*
X38784Y309795D01*
X38680Y309691D01*
X38674Y309670D01*
X38646Y309656D01*
X38403Y309414D01*
X38389Y309386D01*
X38361Y309316D01*
X38396Y309268D01*
X38493Y309254D01*
X38604Y309268D01*
X38680Y309330D01*
X38701Y309351D01*
X38798Y309407D01*
X38833Y309441D01*
X38847Y309469D01*
X38909Y309531D01*
X38937Y309545D01*
X38972Y309580D01*
X38986Y309608D01*
X39048Y309684D01*
X39083Y309719D01*
X39103Y309795D01*
X39131Y309864D01*
X39207Y309940D01*
X39221Y309968D01*
X39284Y310044D01*
X39311Y310058D01*
X39388Y310135D01*
X39402Y310162D01*
X39450Y310197D01*
X39526Y310273D01*
X39533Y310294D01*
X39561Y310308D01*
X39651Y310398D01*
X39665Y310426D01*
X39686Y310447D01*
X39714Y310460D01*
X39776Y310523D01*
X39790Y310551D01*
X39811Y310571D01*
X39838Y310585D01*
X39915Y310662D01*
X39929Y310689D01*
X39949Y310710D01*
X39977Y310724D01*
X40053Y310800D01*
X40060Y310821D01*
X40088Y310835D01*
X40192Y310939D01*
X40199Y310960D01*
X40227Y310974D01*
X40317Y311064D01*
X40331Y311091D01*
X40352Y311112D01*
X40379Y311126D01*
X40407Y311154D01*
X40435Y311168D01*
X40490Y311223D01*
X40560Y311251D01*
X40650Y311286D01*
X40712Y311348D01*
X40740Y311362D01*
X40767Y311390D01*
X40795Y311404D01*
X40830Y311438D01*
X40844Y311466D01*
X40892Y311514D01*
X40920Y311528D01*
X40969Y311577D01*
X40982Y311605D01*
X41031Y311653D01*
X41059Y311667D01*
X41093Y311702D01*
X41107Y311729D01*
X41170Y311792D01*
X41197Y311806D01*
X41232Y311840D01*
X41246Y311868D01*
X41308Y311931D01*
X41329Y311938D01*
X41336Y311958D01*
X41357Y311965D01*
X41371Y311993D01*
X41447Y312069D01*
X41475Y312083D01*
X41530Y312139D01*
X41558Y312152D01*
X41697Y312208D01*
X41773Y312270D01*
X41808Y312305D01*
X41835Y312319D01*
X42154Y312638D01*
X42182Y312652D01*
X42210Y312679D01*
X42238Y312693D01*
X42307Y312721D01*
X42404Y312777D01*
X42432Y312804D01*
X42459Y312818D01*
X42501Y312860D01*
X42529Y312873D01*
X42570Y312915D01*
X42598Y312929D01*
X42626Y312957D01*
X42695Y312985D01*
X42751Y312998D01*
X42827Y313061D01*
X42862Y313095D01*
X42889Y313109D01*
X42917Y313137D01*
X42945Y313151D01*
X43000Y313206D01*
X43028Y313220D01*
X43167Y313276D01*
X43194Y313303D01*
X43222Y313317D01*
X43278Y313373D01*
X43305Y313387D01*
X43382Y313463D01*
X43396Y313491D01*
X43430Y313525D01*
X43458Y313539D01*
X43499Y313581D01*
X43527Y313595D01*
X43555Y313622D01*
X43624Y313650D01*
X43714Y313685D01*
X43798Y313740D01*
X43874Y313775D01*
X43964Y313810D01*
X44047Y313879D01*
X44082Y313914D01*
X44110Y313927D01*
X44186Y313990D01*
X44207Y314011D01*
X44304Y314052D01*
X44484Y314149D01*
X44581Y314191D01*
X44651Y314219D01*
X44748Y314288D01*
X44817Y314316D01*
X44872Y314330D01*
X44970Y314385D01*
X45122Y314454D01*
X45191Y314496D01*
X45247Y314552D01*
X45275Y314565D01*
X45302Y314593D01*
X45330Y314607D01*
X45385Y314662D01*
X45413Y314676D01*
X45538Y314732D01*
X45635Y314787D01*
X45815Y314870D01*
X46023Y314968D01*
X46079Y314981D01*
X46183Y315002D01*
X46252Y315030D01*
X46342Y315079D01*
X46481Y315134D01*
X46509Y315148D01*
X46620Y315217D01*
X46689Y315245D01*
X47369Y315578D01*
X47438Y315619D01*
X47493Y315633D01*
X47590Y315647D01*
X47646Y315661D01*
X47826Y315744D01*
X47923Y315772D01*
X48069Y315807D01*
X48222Y315876D01*
X48339Y315911D01*
X48443Y315931D01*
X48513Y315959D01*
X48658Y316021D01*
X48769Y316049D01*
X48859Y316070D01*
X49012Y316139D01*
X49130Y316174D01*
X49275Y316209D01*
X49352Y316243D01*
X49449Y316285D01*
X49560Y316313D01*
X49650Y316334D01*
X49719Y316361D01*
X49809Y316396D01*
X49920Y316424D01*
X50080Y316444D01*
X50343Y316486D01*
X50454Y316528D01*
X50531Y316549D01*
X50641Y316576D01*
X50815Y316597D01*
X50870Y316611D01*
X50940Y316639D01*
X51030Y316673D01*
X51141Y316701D01*
X51335Y316729D01*
X51390Y316743D01*
X51522Y316791D01*
X51591Y316805D01*
X51716Y316819D01*
X51785Y316833D01*
X51897Y316847D01*
X52035Y316861D01*
X52202Y316888D01*
X52271Y316902D01*
X52389Y316937D01*
X52659Y316958D01*
X52881Y316985D01*
X53075Y316999D01*
X53263Y317020D01*
X53373Y317048D01*
X53512Y317062D01*
X53692Y317076D01*
X54386Y317103D01*
X55086Y317110D01*
X56549Y317103D01*
X56591Y317117D01*
X57354Y317103D01*
X57915Y317082D01*
X58165Y317069D01*
X58359Y317055D01*
X58428Y317041D01*
X58539Y317013D01*
X58914Y316971D01*
X59135Y316944D01*
X59288Y316930D01*
X59351Y316909D01*
X59447Y316881D01*
X59559Y316854D01*
X59767Y316840D01*
X59808Y316826D01*
X59891Y316812D01*
X59933Y316798D01*
X60086Y316756D01*
X60182Y316729D01*
X60363Y316715D01*
X60460Y316701D01*
X60550Y316680D01*
X60606Y316666D01*
X60716Y316625D01*
X60793Y316604D01*
X60848Y316590D01*
X61021Y316569D01*
X61132Y316542D01*
X61202Y316514D01*
X61320Y316479D01*
X61375Y316465D01*
X61549Y316444D01*
X61632Y316431D01*
X61743Y316417D01*
X61798Y316403D01*
X61909Y316361D01*
X61999Y316327D01*
X62055Y316313D01*
X62159Y316292D01*
X62228Y316264D01*
X62374Y316202D01*
X62429Y316188D01*
X62533Y316167D01*
X62644Y316126D01*
X62790Y316063D01*
X62845Y316049D01*
X62949Y316028D01*
X63018Y316001D01*
X63206Y315924D01*
X63303Y315911D01*
X63435Y315862D01*
X63580Y315800D01*
X63636Y315786D01*
X63781Y315751D01*
X64065Y315619D01*
X64274Y315522D01*
X64405Y315501D01*
X64475Y315474D01*
X64592Y315411D01*
X64690Y315370D01*
X64925Y315259D01*
X64981Y315245D01*
X65092Y315231D01*
X65328Y315120D01*
X65480Y315037D01*
X65633Y314968D01*
X65660Y314954D01*
X65737Y314891D01*
X65785Y314857D01*
X65861Y314794D01*
X65896Y314760D01*
X65924Y314746D01*
X66021Y314704D01*
X66111Y314669D01*
X66194Y314614D01*
X66270Y314593D01*
X66326Y314579D01*
X66423Y314565D01*
X66659Y314454D01*
X66756Y314399D01*
X66832Y314337D01*
X66853Y314316D01*
X66881Y314302D01*
X66957Y314240D01*
X66992Y314205D01*
X67144Y314149D01*
X67227Y314094D01*
X67325Y314052D01*
X67449Y313983D01*
X67505Y313927D01*
X67533Y313914D01*
X67609Y313851D01*
X67643Y313817D01*
X67713Y313789D01*
X67803Y313754D01*
X67824Y313733D01*
X68004Y313650D01*
X68101Y313595D01*
X68129Y313567D01*
X68157Y313553D01*
X68337Y313373D01*
X68365Y313359D01*
X68448Y313276D01*
X68580Y313227D01*
X68628Y313193D01*
X68704Y313130D01*
X68787Y313075D01*
X68850Y313012D01*
X68919Y312985D01*
X68975Y312971D01*
X69100Y312873D01*
X69176Y312811D01*
X69197Y312790D01*
X69224Y312777D01*
X69266Y312735D01*
X69342Y312714D01*
X69453Y312645D01*
X69488Y312610D01*
X69516Y312596D01*
X69807Y312305D01*
X69835Y312291D01*
X69918Y312208D01*
X70015Y312180D01*
X70084Y312139D01*
X70160Y312076D01*
X70209Y312041D01*
X70271Y311979D01*
X70285Y311951D01*
X70320Y311917D01*
X70348Y311903D01*
X70382Y311868D01*
X70396Y311840D01*
X70459Y311778D01*
X70486Y311764D01*
X70563Y311702D01*
X70597Y311667D01*
X70687Y311646D01*
X70764Y311598D01*
X70805Y311556D01*
X70833Y311542D01*
X70861Y311514D01*
X70889Y311501D01*
X70909Y311480D01*
X70923Y311452D01*
X71166Y311209D01*
X71187Y311203D01*
X71200Y311175D01*
X71818Y310558D01*
X71838Y310551D01*
X71852Y310523D01*
X72345Y310031D01*
X72365Y310024D01*
X72379Y309996D01*
X72594Y309781D01*
X72622Y309767D01*
X72657Y309732D01*
X72670Y309705D01*
X72733Y309642D01*
X72761Y309628D01*
X72795Y309594D01*
X72809Y309566D01*
X72872Y309490D01*
X72892Y309469D01*
X72920Y309400D01*
X72955Y309310D01*
X73017Y309247D01*
X73031Y309219D01*
X73059Y309192D01*
X73073Y309164D01*
X73121Y309115D01*
X73149Y309102D01*
X73197Y309053D01*
X73211Y309025D01*
X73260Y308977D01*
X73288Y308963D01*
X73336Y308914D01*
X73350Y308887D01*
X73392Y308845D01*
X73405Y308817D01*
X73433Y308790D01*
X73482Y308658D01*
X73517Y308609D01*
X73572Y308554D01*
X73586Y308526D01*
X73877Y308235D01*
X73891Y308207D01*
X73946Y308151D01*
X73960Y308124D01*
X73988Y308055D01*
X74043Y307957D01*
X74106Y307881D01*
X74127Y307860D01*
X74141Y307833D01*
X74182Y307791D01*
X74196Y307763D01*
X74238Y307722D01*
X74258Y307645D01*
X74286Y307576D01*
X74362Y307500D01*
X74376Y307472D01*
X74473Y307347D01*
X74501Y307320D01*
X74515Y307264D01*
X74584Y307139D01*
X74640Y307084D01*
X74654Y307056D01*
X74758Y306952D01*
X74778Y306945D01*
X74792Y306917D01*
X74834Y306876D01*
X74848Y306848D01*
X74889Y306806D01*
X74917Y306737D01*
X74952Y306647D01*
X75007Y306564D01*
X75056Y306446D01*
X75111Y306349D01*
X75167Y306293D01*
X75181Y306266D01*
X75208Y306238D01*
X75222Y306210D01*
X75278Y306155D01*
X75292Y306127D01*
X75333Y306030D01*
X75416Y305877D01*
X75458Y305780D01*
X75514Y305683D01*
X75569Y305628D01*
X75583Y305600D01*
X75645Y305524D01*
X75680Y305475D01*
X75708Y305447D01*
X75742Y305357D01*
X75770Y305288D01*
X75832Y305184D01*
X75867Y305094D01*
X75888Y305045D01*
X75943Y304962D01*
X75985Y304865D01*
X76013Y304795D01*
X76082Y304685D01*
X76124Y304587D01*
X76359Y304130D01*
X76401Y304033D01*
X76436Y303943D01*
X76456Y303922D01*
X76498Y303825D01*
X76512Y303728D01*
X76526Y303672D01*
X76561Y303582D01*
X76623Y303478D01*
X76637Y303423D01*
X76900Y302882D01*
X76914Y302826D01*
X76928Y302715D01*
X77025Y302507D01*
X77053Y302396D01*
X77067Y302313D01*
X77122Y302188D01*
X77164Y302091D01*
X77192Y301980D01*
X77205Y301897D01*
X77275Y301745D01*
X77302Y301675D01*
X77316Y301620D01*
X77337Y301502D01*
X77406Y301349D01*
X77441Y301259D01*
X77455Y301204D01*
X77469Y301107D01*
X77538Y300954D01*
X77566Y300885D01*
X77601Y300725D01*
X77642Y300614D01*
X77677Y300524D01*
X77691Y300469D01*
X77712Y300309D01*
X77739Y300087D01*
X77767Y299976D01*
X77802Y299886D01*
X77843Y299748D01*
X77864Y299574D01*
X77878Y299505D01*
X77920Y299394D01*
X77961Y299241D01*
X77975Y299158D01*
X78003Y298909D01*
X78031Y298798D01*
X78065Y298680D01*
X78093Y298569D01*
X78107Y298472D01*
X78121Y298416D01*
X78134Y298222D01*
X78148Y298181D01*
X78204Y297986D01*
X78239Y297647D01*
X78252Y297536D01*
X78266Y297314D01*
X78287Y297127D01*
X78322Y296967D01*
X78342Y296780D01*
X78363Y296426D01*
X78377Y295899D01*
X78391Y295095D01*
X78426Y295046D01*
X78446Y295026D01*
X78502Y295012D01*
X78710Y295026D01*
X78759Y295074D01*
X78772Y295130D01*
X78759Y295310D01*
X78703Y295435D01*
X78689Y295532D01*
X78668Y295802D01*
X78654Y295955D01*
X78627Y296537D01*
X78613Y296773D01*
X78599Y296967D01*
X78585Y297078D01*
X78571Y297147D01*
X78558Y297203D01*
X78544Y297272D01*
X78516Y297439D01*
X78488Y297716D01*
X78460Y297882D01*
X78446Y297938D01*
X78426Y298000D01*
X78412Y298056D01*
X78398Y298194D01*
X78384Y298250D01*
X78356Y298527D01*
X78342Y298583D01*
X78329Y298694D01*
X78301Y298763D01*
X78259Y298929D01*
X78245Y299068D01*
X78232Y299123D01*
X78218Y299262D01*
X78204Y299304D01*
X78190Y299359D01*
X78148Y299498D01*
X78134Y299554D01*
X78107Y299748D01*
X78086Y299921D01*
X78072Y299976D01*
X78031Y300087D01*
X77996Y300177D01*
X77968Y300289D01*
X77954Y300372D01*
X77885Y300524D01*
X77857Y300621D01*
X77836Y300795D01*
X77822Y300864D01*
X77767Y301017D01*
X77732Y301107D01*
X77705Y301218D01*
X77684Y301294D01*
X77649Y301384D01*
X77607Y301481D01*
X77580Y301578D01*
X77545Y301724D01*
X77469Y301897D01*
X77441Y302008D01*
X77420Y302084D01*
X77379Y302195D01*
X77330Y302313D01*
X77302Y302424D01*
X77288Y302507D01*
X77219Y302618D01*
X77205Y302674D01*
X77053Y302993D01*
X77039Y303131D01*
X76900Y303423D01*
X76831Y303547D01*
X76762Y303700D01*
X76692Y303825D01*
X76623Y303977D01*
X76526Y304185D01*
X76505Y304317D01*
X76477Y304386D01*
X76297Y304747D01*
X76165Y305017D01*
X76040Y305253D01*
X75985Y305309D01*
X75971Y305336D01*
X75909Y305413D01*
X75860Y305503D01*
X75846Y305600D01*
X75832Y305683D01*
X75791Y305752D01*
X75749Y305794D01*
X75735Y305822D01*
X75638Y305947D01*
X75583Y306030D01*
X75562Y306106D01*
X75493Y306217D01*
X75458Y306293D01*
X75423Y306383D01*
X75354Y306467D01*
X75333Y306487D01*
X75319Y306515D01*
X75257Y306591D01*
X75222Y306626D01*
X75208Y306654D01*
X75181Y306723D01*
X75111Y306848D01*
X75042Y306917D01*
X75028Y306945D01*
X74987Y306987D01*
X74973Y307014D01*
X74945Y307042D01*
X74917Y307111D01*
X74882Y307202D01*
X74806Y307278D01*
X74792Y307306D01*
X74730Y307382D01*
X74695Y307416D01*
X74654Y307500D01*
Y307514D01*
X74584Y307638D01*
X74529Y307694D01*
X74515Y307722D01*
X74335Y307902D01*
X74321Y307930D01*
X74279Y307971D01*
X74251Y308041D01*
X74217Y308131D01*
X74154Y308193D01*
X74141Y308221D01*
X74099Y308263D01*
X74085Y308290D01*
X74036Y308325D01*
X73974Y308387D01*
X73960Y308415D01*
X73919Y308457D01*
X73905Y308484D01*
X73877Y308512D01*
X73849Y308581D01*
X73815Y308672D01*
X73738Y308748D01*
X73724Y308776D01*
X73558Y308942D01*
X73544Y308970D01*
X73489Y309025D01*
X73475Y309053D01*
X73447Y309122D01*
X73433Y309178D01*
X73371Y309254D01*
X73336Y309289D01*
X73322Y309316D01*
X73232Y309407D01*
X73204Y309420D01*
X73170Y309469D01*
X72996Y309642D01*
X72969Y309656D01*
X72934Y309691D01*
X72920Y309719D01*
X72858Y309781D01*
X72830Y309795D01*
X72795Y309830D01*
X72782Y309857D01*
X72740Y309899D01*
X72726Y309927D01*
X72670Y309982D01*
X72643Y310079D01*
X72601Y310149D01*
X72546Y310204D01*
X72532Y310232D01*
X72470Y310308D01*
X72393Y310370D01*
X72379Y310398D01*
X72331Y310447D01*
X72303Y310460D01*
X72255Y310509D01*
X72241Y310537D01*
X72192Y310585D01*
X72164Y310599D01*
X72130Y310634D01*
X72116Y310662D01*
X72067Y310710D01*
X72040Y310724D01*
X71991Y310773D01*
X71977Y310800D01*
X71929Y310849D01*
X71901Y310863D01*
X71852Y310911D01*
X71838Y310939D01*
X71790Y310987D01*
X71762Y311001D01*
X71727Y311036D01*
X71714Y311064D01*
X71665Y311112D01*
X71637Y311126D01*
X71561Y311189D01*
X71526Y311223D01*
X71374Y311279D01*
X71318Y311334D01*
X71291Y311348D01*
X71263Y311376D01*
X71235Y311390D01*
X71187Y311438D01*
X71173Y311466D01*
X71138Y311501D01*
X71110Y311514D01*
X71062Y311563D01*
X71048Y311591D01*
X70999Y311639D01*
X70972Y311653D01*
X70909Y311716D01*
X70896Y311743D01*
X70722Y311917D01*
X70694Y311931D01*
X70674Y311951D01*
X70660Y311979D01*
X70583Y312055D01*
X70556Y312069D01*
X70486Y312139D01*
X70459Y312152D01*
X70389Y312180D01*
X70334Y312194D01*
X70258Y312256D01*
X70223Y312291D01*
X70195Y312305D01*
X70029Y312471D01*
X70001Y312485D01*
X69932Y312555D01*
X69876Y312568D01*
X69786Y312603D01*
X69724Y312666D01*
X69696Y312679D01*
X69668Y312707D01*
X69640Y312721D01*
X69564Y312797D01*
X69550Y312825D01*
X69502Y312860D01*
X69460Y312901D01*
X69432Y312915D01*
X69405Y312943D01*
X69377Y312957D01*
X69308Y312985D01*
X69211Y313040D01*
X69183Y313068D01*
X69155Y313081D01*
X68989Y313248D01*
X68961Y313262D01*
X68878Y313345D01*
X68808Y313373D01*
X68753Y313387D01*
X68503Y313581D01*
X68462Y313622D01*
X68406Y313636D01*
X68316Y313671D01*
X68281Y313706D01*
X68254Y313720D01*
X68198Y313775D01*
X68170Y313789D01*
X68101Y313858D01*
X68073Y313872D01*
X67976Y313914D01*
X67879Y313969D01*
X67824Y314025D01*
X67796Y314038D01*
X67768Y314066D01*
X67741Y314080D01*
X67671Y314149D01*
X67602Y314177D01*
X67512Y314212D01*
X67408Y314274D01*
X67338Y314302D01*
X67214Y314371D01*
X67172Y314413D01*
X67144Y314427D01*
X67068Y314489D01*
X67019Y314538D01*
X66950Y314565D01*
X66860Y314600D01*
X66777Y314656D01*
X66700Y314690D01*
X66603Y314732D01*
X66576Y314746D01*
X66492Y314801D01*
X66395Y314843D01*
X66305Y314877D01*
X66284Y314898D01*
X66257Y314912D01*
X66104Y314981D01*
X65979Y315051D01*
X65827Y315120D01*
X65591Y315231D01*
X65535Y315245D01*
X65425Y315259D01*
X65328Y315314D01*
X65230Y315356D01*
X65140Y315391D01*
X65057Y315446D01*
X64814Y315564D01*
X64440Y315744D01*
X64343Y315772D01*
X64246Y315786D01*
X63955Y315924D01*
X63747Y316021D01*
X63650Y316035D01*
X63518Y316084D01*
X63448Y316112D01*
X63372Y316146D01*
X63317Y316160D01*
X63171Y316195D01*
X63102Y316223D01*
X63025Y316257D01*
X62956Y316285D01*
X62901Y316299D01*
X62797Y316320D01*
X62686Y316361D01*
X62609Y316396D01*
X62540Y316424D01*
X62443Y316438D01*
X62311Y316486D01*
X62221Y316521D01*
X62152Y316549D01*
X62055Y316562D01*
X61999Y316576D01*
X61847Y316590D01*
X61722Y316646D01*
X61652Y316673D01*
X61542Y316701D01*
X61458Y316715D01*
X61334Y316770D01*
X61264Y316798D01*
X61167Y316826D01*
X60994Y316847D01*
X60925Y316861D01*
X60813Y316902D01*
X60737Y316923D01*
X60682Y316937D01*
X60508Y316958D01*
X60356Y316971D01*
X60106Y317013D01*
X60051Y317027D01*
X59974Y317048D01*
X59919Y317062D01*
X59725Y317089D01*
X59538Y317110D01*
X59454Y317124D01*
X59344Y317138D01*
X59274Y317152D01*
X59219Y317166D01*
X59142Y317186D01*
X58976Y317214D01*
X58622Y317249D01*
X58435Y317270D01*
X58338Y317283D01*
X58262Y317304D01*
X58193Y317318D01*
X58005Y317339D01*
X57742Y317353D01*
X57561Y317367D01*
X57457Y317374D01*
X57395Y317367D01*
X57354Y317381D01*
X57069Y317401D01*
X56930Y317415D01*
X56778Y317443D01*
X56667Y317457D01*
X56417Y317471D01*
X56265Y317485D01*
X56001Y317498D01*
X55634Y317505D01*
D02*
G37*
G36*
X52444Y307784D02*
X44449Y307777D01*
X44290Y307784D01*
X44248Y307770D01*
X44110Y307756D01*
X43714Y307736D01*
X43666Y307715D01*
X43562Y307611D01*
X43548Y307555D01*
X43527Y307132D01*
X43506Y306945D01*
X43499Y295525D01*
X43513Y295358D01*
X43548Y295310D01*
X43569Y295289D01*
X43624Y295275D01*
X46356Y295289D01*
X46405Y295338D01*
X46419Y295393D01*
X46426Y296218D01*
X46419Y296267D01*
X46432Y296308D01*
X46419Y296447D01*
X46432Y296877D01*
X46426Y304802D01*
X46439Y304927D01*
X46467Y304969D01*
X46537Y304997D01*
X48755Y304983D01*
X48804Y304948D01*
X48818Y304893D01*
X48825Y304816D01*
X48818Y304740D01*
X48832Y304698D01*
X48825Y304026D01*
X48832Y303950D01*
X48818Y303908D01*
X48825Y303665D01*
X48818Y303520D01*
X48832Y303478D01*
X48825Y303277D01*
X48832Y296516D01*
Y296502D01*
X48846Y295934D01*
X48859Y295892D01*
X48873Y295490D01*
X48943Y295393D01*
X48977Y295358D01*
X49005Y295345D01*
X49074Y295317D01*
X49546Y295303D01*
X49587Y295289D01*
X49685Y295275D01*
X49893Y295289D01*
X49934Y295275D01*
X51404Y295289D01*
X51467Y295338D01*
X51480Y295393D01*
X51494Y304920D01*
X51543Y304983D01*
X51640Y304997D01*
X52195Y305010D01*
X52236Y305024D01*
X52347Y305038D01*
X52375Y305066D01*
X52403Y305080D01*
X52465Y305142D01*
X52479Y305170D01*
X52507Y305239D01*
X52527Y305704D01*
X52541Y305773D01*
X52548Y305947D01*
X52534Y305988D01*
X52548Y306127D01*
X52534Y307722D01*
X52514Y307756D01*
X52444Y307784D01*
D02*
G37*
G36*
X67311D02*
X67269Y307770D01*
X67130Y307784D01*
X61223Y307770D01*
X61181Y307756D01*
X60758Y307736D01*
X60647Y307694D01*
X60494Y307638D01*
X60446Y307604D01*
X60418Y307576D01*
X60391Y307562D01*
X60363Y307534D01*
X60335Y307521D01*
X60273Y307458D01*
X60259Y307430D01*
X60224Y307396D01*
X60196Y307382D01*
X60120Y307306D01*
X60106Y307278D01*
X60086Y307257D01*
X60058Y307243D01*
X59995Y307181D01*
X59981Y307153D01*
X59961Y307132D01*
X59933Y307118D01*
X59857Y307042D01*
X59843Y307014D01*
X59794Y306980D01*
X59732Y306917D01*
X59718Y306890D01*
X59697Y306869D01*
X59669Y306855D01*
X59607Y306793D01*
X59593Y306765D01*
X59559Y306730D01*
X59531Y306716D01*
X59454Y306640D01*
X59441Y306612D01*
X59420Y306591D01*
X59392Y306577D01*
X59330Y306515D01*
X59316Y306487D01*
X59295Y306467D01*
X59267Y306453D01*
X59205Y306390D01*
X59191Y306363D01*
X59156Y306328D01*
X59129Y306314D01*
X59066Y306252D01*
X59052Y306224D01*
X59032Y306203D01*
X59004Y306189D01*
X58941Y306127D01*
X58927Y306099D01*
X58844Y305974D01*
X58816Y305863D01*
X58803Y305683D01*
X58789Y305641D01*
X58775Y305586D01*
X58747Y305517D01*
X58733Y305461D01*
X58720Y305322D01*
X58699Y304969D01*
X58685Y304553D01*
X58678Y298375D01*
X58692Y298333D01*
X58706Y297764D01*
X58720Y297723D01*
X58733Y297446D01*
X58789Y297321D01*
X58810Y297231D01*
X58830Y297099D01*
X58900Y296988D01*
X58927Y296919D01*
X58969Y296808D01*
X59032Y296731D01*
X59066Y296697D01*
X59080Y296669D01*
X59156Y296593D01*
X59184Y296579D01*
X59253Y296509D01*
X59323Y296482D01*
X59413Y296447D01*
X59461Y296412D01*
X59496Y296364D01*
X59531Y296329D01*
X59559Y296315D01*
X59579Y296294D01*
X59607Y296225D01*
X59628Y296149D01*
X59649Y296128D01*
X59662Y296100D01*
X59697Y296066D01*
X59725Y296052D01*
X59760Y296003D01*
X59794Y295969D01*
X59968Y295906D01*
X59995Y295879D01*
X60009Y295851D01*
X60058Y295802D01*
X60086Y295788D01*
X60106Y295767D01*
X60134Y295698D01*
X60169Y295608D01*
X60203Y295560D01*
X60252Y295525D01*
X60273Y295504D01*
X60286Y295476D01*
X60321Y295442D01*
X60391Y295414D01*
X60522Y295365D01*
X60612Y295331D01*
X60793Y295317D01*
X61146Y295296D01*
X61729Y295282D01*
X65633Y295275D01*
X65647D01*
X68198Y295289D01*
X68233Y295324D01*
X68261Y295435D01*
X68247Y297737D01*
X68198Y297785D01*
X68143Y297799D01*
X63268Y297806D01*
X63095Y297799D01*
X63053Y297813D01*
X62824Y297806D01*
X62665Y297813D01*
X62623Y297799D01*
X62491Y297820D01*
X62457Y297827D01*
X62415Y297813D01*
X62304Y297799D01*
X62263Y297813D01*
X62152Y297841D01*
X61791Y297855D01*
X61659Y297986D01*
X61646Y298042D01*
X61632Y298139D01*
X61618Y298458D01*
X61604Y298500D01*
X61618Y298735D01*
X61604Y298777D01*
X61611Y299657D01*
X61604Y299803D01*
X61618Y299845D01*
X61632Y299942D01*
X61646Y300247D01*
X61715Y300344D01*
X61777Y300406D01*
X61888Y300434D01*
X62235Y300448D01*
X62277Y300462D01*
X62505Y300455D01*
X67179Y300469D01*
X67262Y300483D01*
X67304Y300524D01*
X67331Y300621D01*
X67325Y301641D01*
X67331Y301772D01*
X67318Y301814D01*
X67304Y301994D01*
X67290Y302133D01*
X67283Y302292D01*
X67290Y302341D01*
X67276Y302383D01*
X67234Y302452D01*
X67158Y302528D01*
X67061Y302556D01*
X66603Y302570D01*
X66562Y302584D01*
X66465Y302597D01*
X66284Y302584D01*
X66187Y302597D01*
X66014Y302591D01*
X61687Y302604D01*
X61639Y302625D01*
X61604Y302701D01*
X61611Y304151D01*
X61604Y304310D01*
X61618Y304352D01*
X61611Y304580D01*
X61625Y304650D01*
X61639Y304886D01*
X61652Y305066D01*
X61673Y305087D01*
X61687Y305114D01*
X61764Y305191D01*
X61791Y305205D01*
X61833Y305219D01*
X62214Y305239D01*
X62270Y305253D01*
X62401Y305260D01*
X62443Y305246D01*
X62693Y305260D01*
X62734Y305246D01*
X62873Y305260D01*
X68184Y305274D01*
X68233Y305309D01*
X68261Y305406D01*
X68254Y306550D01*
X68261Y306709D01*
X68247Y306751D01*
X68261Y306987D01*
X68247Y307028D01*
X68233Y307084D01*
X68212Y307562D01*
X68191Y307611D01*
X68163Y307638D01*
X68150Y307666D01*
X68129Y307687D01*
X68101Y307701D01*
X68073Y307729D01*
X68018Y307742D01*
X67553Y307763D01*
X67484Y307777D01*
X67311Y307784D01*
D02*
G37*
G36*
X36690D02*
X36649Y307770D01*
X36510Y307784D01*
X28120Y307770D01*
X28071Y307722D01*
X28058Y307624D01*
X28065Y305940D01*
X28058Y305794D01*
X28071Y305752D01*
X28085Y305655D01*
X28106Y305219D01*
X28127Y305170D01*
X28182Y305114D01*
X28189Y305094D01*
X28217Y305080D01*
X28245Y305052D01*
X28342Y305038D01*
X28765Y305017D01*
X28834Y305004D01*
X29008Y304997D01*
X29049Y305010D01*
X29188Y304997D01*
X30041Y304990D01*
X30159Y304997D01*
X30200Y304983D01*
X30429Y304990D01*
X30602Y304983D01*
X30644Y304997D01*
X30762Y304976D01*
X31199Y304941D01*
X31330Y304809D01*
X31344Y304754D01*
Y304629D01*
Y304615D01*
X31358Y304518D01*
X31372Y304310D01*
X31386Y304268D01*
X31372Y304130D01*
X31386Y303922D01*
X31372Y303880D01*
X31386Y303645D01*
X31372Y303603D01*
X31386Y303464D01*
X31400Y295338D01*
X31435Y295303D01*
X31490Y295289D01*
X31587Y295275D01*
X33078Y295282D01*
X33237Y295275D01*
X33279Y295289D01*
X33501Y295275D01*
X33542Y295289D01*
X33639Y295303D01*
X34076Y295324D01*
X34146Y295352D01*
X34243Y295449D01*
X34270Y295546D01*
X34284Y295989D01*
X34298Y296031D01*
X34312Y296170D01*
X34298Y296308D01*
X34312Y296406D01*
X34305Y296579D01*
X34319Y303818D01*
X34326Y303894D01*
X34312Y303936D01*
X34326Y304185D01*
X34312Y304227D01*
X34326Y304380D01*
X34340Y304421D01*
X34347Y304692D01*
X34340Y304698D01*
X34354Y304740D01*
X34367Y304809D01*
X34499Y304941D01*
X34596Y304955D01*
X34811Y304962D01*
X34846Y304955D01*
X34887Y304969D01*
X35005Y304990D01*
X35082Y304997D01*
X35123Y304983D01*
X35380Y304990D01*
X35512Y304983D01*
X35553Y304997D01*
X35740Y304990D01*
X36462Y305004D01*
X36538Y305010D01*
X36579Y304997D01*
X36788Y305010D01*
X36829Y305024D01*
X37294Y305045D01*
X37467Y305149D01*
X37502Y305184D01*
X37557Y305281D01*
X37599Y305378D01*
X37620Y305856D01*
X37633Y305926D01*
X37640Y306057D01*
X37626Y306099D01*
X37640Y306376D01*
X37626Y306418D01*
X37640Y306598D01*
X37626Y306848D01*
X37640Y306890D01*
X37626Y307042D01*
X37613Y307084D01*
X37592Y307562D01*
X37571Y307611D01*
X37509Y307687D01*
X37425Y307742D01*
X36933Y307763D01*
X36864Y307777D01*
X36690Y307784D01*
D02*
G37*
G36*
X41475D02*
X39214D01*
X38909Y307770D01*
X38861Y307736D01*
X38847Y307680D01*
X38840Y307631D01*
X38847Y307541D01*
X38833Y307500D01*
X38847Y307403D01*
X38861Y295338D01*
X38909Y295289D01*
X39048Y295275D01*
X41558Y295289D01*
X41606Y295324D01*
X41634Y295421D01*
X41620Y307722D01*
X41572Y307770D01*
X41475Y307784D01*
D02*
G37*
G36*
X76796Y293680D02*
X76755Y293666D01*
X76547Y293680D01*
X76505Y293666D01*
X76276Y293673D01*
X76193Y293660D01*
X75999Y293646D01*
X75950Y293639D01*
X75936D01*
X75777Y293632D01*
X75701Y293639D01*
X75659Y293625D01*
X75631Y293611D01*
X75590Y293570D01*
X75562Y293556D01*
X75541Y293535D01*
X75527Y293507D01*
X75500Y293438D01*
X75479Y293029D01*
X75465Y292918D01*
X75451Y281477D01*
X75444Y281387D01*
X75458Y281345D01*
X75472Y281220D01*
X75507Y281185D01*
X75604Y281172D01*
X83404Y281178D01*
X83591Y281172D01*
X83633Y281185D01*
X83772Y281199D01*
X84167Y281220D01*
X84271Y281283D01*
X84299Y281296D01*
X84347Y281331D01*
X84361Y281359D01*
X85706Y282704D01*
X85720Y282732D01*
X85803Y282815D01*
X85831Y282884D01*
X85880Y283016D01*
X85900Y283078D01*
X85914Y283134D01*
X85935Y283460D01*
X85956Y283869D01*
X85970Y285089D01*
X85963Y290754D01*
X85970Y290844D01*
X85956Y290886D01*
X85963Y291129D01*
X85949Y291198D01*
X85921Y291572D01*
X85914Y291635D01*
X85928Y291677D01*
X85914Y291732D01*
X85845Y291857D01*
X85783Y291933D01*
X85706Y291996D01*
X85693Y292023D01*
X85630Y292086D01*
X85602Y292099D01*
X85568Y292134D01*
X85554Y292162D01*
X85491Y292224D01*
X85464Y292238D01*
X85443Y292259D01*
X85429Y292287D01*
X85367Y292349D01*
X85339Y292363D01*
X85304Y292398D01*
X85290Y292425D01*
X85228Y292488D01*
X85200Y292502D01*
X85179Y292522D01*
X85166Y292550D01*
X85103Y292613D01*
X85075Y292626D01*
X85041Y292661D01*
X85027Y292689D01*
X84964Y292751D01*
X84937Y292765D01*
X84902Y292800D01*
X84888Y292827D01*
X84826Y292890D01*
X84798Y292904D01*
X84777Y292925D01*
X84763Y292952D01*
X84701Y293015D01*
X84673Y293029D01*
X84639Y293063D01*
X84625Y293091D01*
X84562Y293153D01*
X84535Y293167D01*
X84514Y293188D01*
X84500Y293216D01*
X84437Y293278D01*
X84410Y293292D01*
X84375Y293327D01*
X84361Y293354D01*
X84299Y293417D01*
X84271Y293431D01*
X84202Y293500D01*
X84174Y293514D01*
X84077Y293556D01*
X83987Y293590D01*
X83917Y293618D01*
X83834Y293632D01*
X83799Y293639D01*
X83758Y293625D01*
X83716Y293639D01*
X83335Y293660D01*
X82725Y293673D01*
X76796Y293680D01*
D02*
G37*
G36*
X47799D02*
X47757Y293666D01*
X47487Y293673D01*
X47480Y293666D01*
X47091Y293680D01*
X41752Y293666D01*
X41711Y293653D01*
X41315Y293632D01*
X41163Y293618D01*
X41093Y293590D01*
X40982Y293549D01*
X40913Y293521D01*
X40865Y293486D01*
X40823Y293445D01*
X40795Y293431D01*
X40767Y293403D01*
X40740Y293389D01*
X40719Y293368D01*
X40705Y293341D01*
X40643Y293278D01*
X40615Y293264D01*
X40580Y293230D01*
X40566Y293202D01*
X40504Y293140D01*
X40476Y293126D01*
X40442Y293091D01*
X40428Y293063D01*
X40365Y293001D01*
X40338Y292987D01*
X40317Y292966D01*
X40303Y292938D01*
X40227Y292862D01*
X40199Y292848D01*
X40178Y292827D01*
X40164Y292800D01*
X40102Y292737D01*
X40074Y292724D01*
X40040Y292689D01*
X40026Y292661D01*
X39963Y292599D01*
X39936Y292585D01*
X39915Y292564D01*
X39901Y292536D01*
X39838Y292474D01*
X39811Y292460D01*
X39776Y292425D01*
X39762Y292398D01*
X39714Y292349D01*
X39686Y292335D01*
X39651Y292301D01*
X39637Y292273D01*
X39575Y292210D01*
X39547Y292197D01*
X39513Y292162D01*
X39499Y292134D01*
X39450Y292086D01*
X39422Y292072D01*
X39374Y292023D01*
X39332Y291954D01*
X39263Y291857D01*
X39249Y291801D01*
X39228Y291670D01*
X39187Y291559D01*
X39166Y291482D01*
X39152Y291427D01*
X39131Y291032D01*
X39117Y290643D01*
X39110Y284077D01*
X39124Y284035D01*
X39138Y283453D01*
X39152Y283411D01*
X39166Y283203D01*
X39235Y283051D01*
X39249Y282995D01*
X39318Y282898D01*
X39360Y282857D01*
X39374Y282829D01*
X39450Y282752D01*
X39478Y282739D01*
X39499Y282718D01*
X39513Y282690D01*
X39589Y282614D01*
X39616Y282600D01*
X39651Y282551D01*
X39714Y282489D01*
X39741Y282475D01*
X39762Y282454D01*
X39776Y282427D01*
X39852Y282350D01*
X39880Y282337D01*
X39901Y282316D01*
X39915Y282288D01*
X39991Y282212D01*
X40019Y282198D01*
X40053Y282149D01*
X40116Y282087D01*
X40143Y282073D01*
X40178Y282024D01*
X40254Y281948D01*
X40282Y281934D01*
X40317Y281886D01*
X40379Y281823D01*
X40407Y281810D01*
X40428Y281789D01*
X40442Y281761D01*
X40518Y281685D01*
X40546Y281671D01*
X40566Y281650D01*
X40580Y281622D01*
X40657Y281546D01*
X40684Y281532D01*
X40719Y281484D01*
X40781Y281421D01*
X40809Y281407D01*
X40830Y281387D01*
X40844Y281359D01*
X40865Y281324D01*
X40892Y281310D01*
X41045Y281213D01*
X41523Y281192D01*
X41606Y281178D01*
X41794Y281172D01*
X41835Y281185D01*
X41932Y281172D01*
X48631Y281185D01*
X48665Y281220D01*
X48693Y281331D01*
X48686Y282600D01*
X48693Y282718D01*
X48679Y282759D01*
X48686Y283002D01*
X48672Y283085D01*
X48658Y283279D01*
X48644Y283460D01*
X48637Y283508D01*
X48651Y283550D01*
X48637Y283605D01*
X48624Y283647D01*
X48561Y283723D01*
X48534Y283751D01*
X48464Y283779D01*
X48014Y283800D01*
X47826Y283820D01*
X47667Y283813D01*
X43909Y283827D01*
X43090Y283841D01*
X42716Y283855D01*
X42411Y283869D01*
X42355Y283883D01*
X42286Y283911D01*
X42196Y283945D01*
X42140Y283959D01*
X42050Y284008D01*
X42036Y284063D01*
X42043Y290061D01*
X42036Y290220D01*
X42050Y290262D01*
X42064Y290317D01*
X42078Y290678D01*
X42140Y290754D01*
X42210Y290824D01*
X42321Y290851D01*
X42681Y290865D01*
X42723Y290879D01*
X42952Y290872D01*
X46696Y290886D01*
X47514Y290900D01*
X48097Y290942D01*
X48152Y290955D01*
X48270Y290990D01*
X48326Y291004D01*
X48464Y291018D01*
X48631Y291032D01*
X48665Y291066D01*
X48693Y291177D01*
X48686Y292446D01*
X48693Y292578D01*
X48679Y292619D01*
X48686Y292862D01*
X48672Y292931D01*
X48644Y293320D01*
X48637Y293368D01*
X48651Y293410D01*
X48637Y293465D01*
X48624Y293493D01*
X48561Y293570D01*
X48520Y293611D01*
X48423Y293639D01*
X48326Y293625D01*
X48284Y293639D01*
X47944Y293660D01*
X47861Y293673D01*
X47799Y293680D01*
D02*
G37*
G36*
X58685D02*
X58643Y293666D01*
X58539Y293646D01*
X58359Y293632D01*
X58310Y293611D01*
X58283Y293583D01*
X58255Y293570D01*
X58158Y293500D01*
X58088Y293417D01*
X58026Y293368D01*
X58012Y293341D01*
X57936Y293264D01*
X57908Y293251D01*
X57887Y293230D01*
X57874Y293202D01*
X57811Y293140D01*
X57783Y293126D01*
X57749Y293091D01*
X57735Y293063D01*
X57673Y293001D01*
X57645Y292987D01*
X57624Y292966D01*
X57610Y292938D01*
X57534Y292862D01*
X57506Y292848D01*
X57485Y292827D01*
X57471Y292800D01*
X57409Y292737D01*
X57381Y292724D01*
X57360Y292703D01*
X57347Y292675D01*
X57270Y292599D01*
X57242Y292585D01*
X57222Y292564D01*
X57208Y292536D01*
X57146Y292474D01*
X57118Y292460D01*
X57083Y292425D01*
X57069Y292398D01*
X57007Y292335D01*
X56979Y292321D01*
X56958Y292301D01*
X56944Y292273D01*
X56868Y292197D01*
X56840Y292183D01*
X56820Y292162D01*
X56806Y292134D01*
X56743Y292072D01*
X56716Y292058D01*
X56695Y292037D01*
X56681Y292009D01*
X56605Y291933D01*
X56577Y291919D01*
X56556Y291898D01*
X56542Y291871D01*
X56480Y291808D01*
X56452Y291794D01*
X56417Y291760D01*
X56403Y291732D01*
X56341Y291670D01*
X56313Y291656D01*
X56293Y291635D01*
X56279Y291607D01*
X56203Y291531D01*
X56175Y291517D01*
X56154Y291496D01*
X56140Y291469D01*
X56064Y291392D01*
X56036Y291378D01*
X55932Y291233D01*
X55967Y291170D01*
X56064Y291157D01*
X56168Y291150D01*
X56674Y291157D01*
X56716Y291143D01*
X56896Y291157D01*
X57416Y291136D01*
X57527Y291150D01*
X57561Y291157D01*
X57603Y291143D01*
X57742Y291129D01*
X58054Y291108D01*
X58130Y291059D01*
X58220Y290969D01*
X58234Y290914D01*
X58255Y290532D01*
X58269Y290477D01*
X58276Y290345D01*
X58262Y290304D01*
X58276Y290054D01*
X58262Y290012D01*
X58276Y289915D01*
X58269Y288660D01*
X58276Y288487D01*
X58262Y288445D01*
X58276Y288223D01*
X58248Y288154D01*
X58227Y287759D01*
X58158Y287648D01*
X58102Y287565D01*
X58075Y287551D01*
X57964Y287481D01*
X57867Y287454D01*
X57790Y287461D01*
X57541Y287447D01*
X57485Y287433D01*
X57326Y287426D01*
X57284Y287440D01*
X57146Y287426D01*
X54310Y287433D01*
X54136Y287426D01*
X54067Y287454D01*
X53810Y287461D01*
X53734Y287454D01*
X53692Y287468D01*
X53665Y287481D01*
X53581Y287537D01*
X53554Y287551D01*
X53491Y287599D01*
X53477Y287627D01*
X53408Y287724D01*
X53366Y287821D01*
X53353Y288085D01*
X53339Y288251D01*
X53290Y288300D01*
X53235Y288286D01*
X53207Y288258D01*
X53179Y288244D01*
X53013Y288078D01*
X52985Y288064D01*
X52964Y288043D01*
X52950Y288015D01*
X52874Y287939D01*
X52846Y287925D01*
X52777Y287842D01*
X52722Y287787D01*
X52694Y287773D01*
X52659Y287724D01*
X52611Y287676D01*
X52583Y287662D01*
X52548Y287613D01*
X52486Y287551D01*
X52458Y287537D01*
X52437Y287516D01*
X52424Y287488D01*
X52347Y287412D01*
X52319Y287398D01*
X52299Y287377D01*
X52285Y287350D01*
X52208Y287273D01*
X52188Y287267D01*
X52174Y287239D01*
X52084Y287149D01*
X52056Y287135D01*
X52021Y287100D01*
X52007Y287072D01*
X51931Y286996D01*
X51910Y286989D01*
X51897Y286961D01*
X51806Y286871D01*
X51779Y286857D01*
X51744Y286809D01*
X51681Y286747D01*
X51654Y286733D01*
X51633Y286712D01*
X51619Y286684D01*
X51543Y286608D01*
X51515Y286594D01*
X51494Y286573D01*
X51480Y286545D01*
X51390Y286455D01*
X51370Y286448D01*
X51356Y286421D01*
X51266Y286330D01*
X51238Y286317D01*
X51203Y286268D01*
X51155Y286220D01*
X51127Y286206D01*
X51106Y286185D01*
X51092Y286157D01*
X51016Y286081D01*
X50988Y286067D01*
X50967Y286046D01*
X50953Y286018D01*
X50877Y285942D01*
X50849Y285928D01*
X50815Y285880D01*
X50739Y285804D01*
X50711Y285790D01*
X50690Y285769D01*
X50593Y285561D01*
X50607Y285450D01*
X50593Y285408D01*
X50572Y285082D01*
X50558Y284999D01*
X50551Y284923D01*
X50565Y284881D01*
X50558Y284625D01*
X50565Y284479D01*
X50551Y284438D01*
X50558Y284250D01*
X50551Y281317D01*
X50565Y281276D01*
X50579Y281220D01*
X50614Y281185D01*
X50669Y281172D01*
X53290Y281185D01*
X53325Y281220D01*
X53353Y281331D01*
X53359Y283793D01*
X53353Y283897D01*
X53366Y283938D01*
X53380Y284535D01*
X53394Y284576D01*
X53408Y284729D01*
X53464Y284853D01*
X53477Y284909D01*
X53505Y284978D01*
X53540Y285013D01*
X53595Y285027D01*
X53727Y285075D01*
X53796Y285103D01*
X53852Y285117D01*
X54157Y285131D01*
X54545Y285145D01*
X55350Y285159D01*
X56272Y285166D01*
X56313Y285152D01*
X57464Y285138D01*
X57506Y285124D01*
X57825Y285110D01*
X57977Y285041D01*
X58068Y285020D01*
X58116Y284985D01*
X58151Y284909D01*
X58172Y284819D01*
X58234Y284673D01*
X58255Y284250D01*
X58269Y283696D01*
X58283Y281283D01*
X58296Y281227D01*
X58338Y281185D01*
X58394Y281172D01*
X61015Y281185D01*
X61049Y281220D01*
X61063Y281276D01*
X61070Y282115D01*
X61063Y282163D01*
X61077Y282205D01*
X61063Y282302D01*
X61077Y282857D01*
Y290096D01*
Y290109D01*
X61063Y290248D01*
X61049Y291191D01*
X61035Y291233D01*
X61021Y291607D01*
X60966Y291732D01*
X60952Y291787D01*
X60925Y291857D01*
X60911Y291884D01*
X60841Y291954D01*
X60827Y291982D01*
X60765Y292058D01*
X60689Y292120D01*
X60626Y292197D01*
X60550Y292259D01*
X60488Y292335D01*
X60411Y292398D01*
X60349Y292474D01*
X60321Y292488D01*
X60273Y292536D01*
X60259Y292564D01*
X60210Y292613D01*
X60182Y292626D01*
X60134Y292675D01*
X60120Y292703D01*
X60086Y292737D01*
X60058Y292751D01*
X60009Y292800D01*
X59995Y292827D01*
X59947Y292876D01*
X59919Y292890D01*
X59871Y292938D01*
X59857Y292966D01*
X59808Y293015D01*
X59780Y293029D01*
X59732Y293077D01*
X59718Y293105D01*
X59683Y293140D01*
X59656Y293153D01*
X59607Y293202D01*
X59593Y293230D01*
X59545Y293278D01*
X59517Y293292D01*
X59468Y293341D01*
X59454Y293368D01*
X59406Y293417D01*
X59378Y293431D01*
X59344Y293465D01*
X59330Y293493D01*
X59281Y293542D01*
X59253Y293556D01*
X59156Y293625D01*
X59101Y293639D01*
X58907Y293653D01*
X58865Y293666D01*
X58685Y293680D01*
D02*
G37*
G36*
X54150Y314981D02*
X54108Y314968D01*
X54039Y314926D01*
X54018Y314850D01*
X54011Y296385D01*
X54018Y296211D01*
X54004Y296170D01*
X54018Y295962D01*
X54004Y295920D01*
X54018Y295684D01*
X53991Y295615D01*
X53984Y295525D01*
X53991Y295449D01*
X53977Y295407D01*
X53963Y295199D01*
X53893Y295102D01*
X53852Y295033D01*
X53831Y295012D01*
X53803Y294998D01*
X53741Y294935D01*
X53727Y294908D01*
X53706Y294887D01*
X53678Y294873D01*
X53616Y294811D01*
X53602Y294783D01*
X53568Y294748D01*
X53540Y294734D01*
X53477Y294672D01*
X53464Y294644D01*
X53429Y294610D01*
X53401Y294596D01*
X53353Y294547D01*
X53339Y294519D01*
X53304Y294485D01*
X53276Y294471D01*
X53214Y294408D01*
X53200Y294381D01*
X53165Y294346D01*
X53138Y294332D01*
X53075Y294270D01*
X53061Y294242D01*
X53027Y294207D01*
X52957Y294166D01*
X52888Y294096D01*
X52791Y294069D01*
X52722Y294027D01*
X52666Y293972D01*
X52638Y293958D01*
X52562Y293895D01*
X52500Y293819D01*
X52424Y293757D01*
X52410Y293729D01*
X52347Y293666D01*
X52319Y293653D01*
X52285Y293618D01*
X52271Y293590D01*
X52222Y293542D01*
X52195Y293528D01*
X52160Y293493D01*
X52146Y293465D01*
X52084Y293403D01*
X52056Y293389D01*
X52021Y293354D01*
X52007Y293327D01*
X51959Y293278D01*
X51931Y293264D01*
X51897Y293230D01*
X51883Y293202D01*
X51820Y293140D01*
X51792Y293126D01*
X51758Y293091D01*
X51744Y293063D01*
X51695Y293015D01*
X51668Y293001D01*
X51633Y292966D01*
X51619Y292938D01*
X51557Y292876D01*
X51529Y292862D01*
X51494Y292827D01*
X51480Y292800D01*
X51432Y292751D01*
X51404Y292737D01*
X51356Y292689D01*
X51342Y292661D01*
X51293Y292613D01*
X51266Y292599D01*
X51231Y292564D01*
X51217Y292536D01*
X51155Y292474D01*
X51127Y292460D01*
X51092Y292425D01*
X51078Y292398D01*
X51016Y292335D01*
X50988Y292321D01*
X50953Y292287D01*
X50940Y292259D01*
X50891Y292210D01*
X50863Y292197D01*
X50829Y292162D01*
X50815Y292134D01*
X50766Y292086D01*
X50739Y292072D01*
X50690Y292023D01*
X50676Y291996D01*
X50628Y291947D01*
X50600Y291933D01*
X50565Y291898D01*
X50551Y291871D01*
X50489Y291808D01*
X50461Y291794D01*
X50427Y291760D01*
X50413Y291732D01*
X50350Y291670D01*
X50322Y291656D01*
X50302Y291635D01*
X50288Y291607D01*
X50225Y291545D01*
X50198Y291531D01*
X50149Y291482D01*
X50135Y291455D01*
X50101Y291420D01*
X50073Y291406D01*
X50024Y291357D01*
X50010Y291330D01*
X49962Y291281D01*
X49934Y291267D01*
X49900Y291233D01*
X49886Y291205D01*
X49823Y291143D01*
X49795Y291129D01*
X49761Y291094D01*
X49747Y291066D01*
X49685Y291004D01*
X49657Y290990D01*
X49636Y290969D01*
X49622Y290942D01*
X49560Y290879D01*
X49532Y290865D01*
X49483Y290817D01*
X49470Y290789D01*
X49435Y290754D01*
X49407Y290740D01*
X49359Y290692D01*
X49345Y290664D01*
X49296Y290616D01*
X49268Y290602D01*
X49234Y290567D01*
X49220Y290539D01*
X49158Y290477D01*
X49130Y290463D01*
X49095Y290428D01*
X49081Y290401D01*
X49033Y290352D01*
X49005Y290338D01*
X48956Y290290D01*
X48943Y290262D01*
X48894Y290213D01*
X48866Y290200D01*
X48832Y290165D01*
X48818Y290137D01*
X48755Y290075D01*
X48728Y290061D01*
X48707Y290040D01*
X48693Y290012D01*
X48631Y289950D01*
X48603Y289936D01*
X48568Y289901D01*
X48554Y289874D01*
X48492Y289811D01*
X48464Y289797D01*
X48429Y289763D01*
X48416Y289735D01*
X48353Y289673D01*
X48326Y289659D01*
X48305Y289638D01*
X48291Y289610D01*
X48228Y289548D01*
X48201Y289534D01*
X48166Y289499D01*
X48152Y289471D01*
X48090Y289409D01*
X48062Y289395D01*
X48027Y289361D01*
X48014Y289333D01*
X47951Y289270D01*
X47923Y289256D01*
X47902Y289236D01*
X47889Y289208D01*
X47861Y289180D01*
X47847Y289153D01*
X47792Y289097D01*
X47778Y289069D01*
X47750Y289000D01*
X47736Y288944D01*
X47681Y288820D01*
X47667Y288681D01*
X47646Y288272D01*
X47632Y287800D01*
X47625Y287447D01*
X47639Y287405D01*
X47653Y286740D01*
X47667Y286698D01*
X47681Y286421D01*
X47736Y286296D01*
X47750Y286240D01*
X47819Y286115D01*
X47875Y286060D01*
X47889Y286032D01*
X47937Y285970D01*
X47965Y285956D01*
X48041Y285880D01*
X48048Y285859D01*
X48076Y285845D01*
X48131Y285790D01*
X48159Y285776D01*
X48187Y285748D01*
X48242Y285734D01*
X48270Y285762D01*
X48298Y285776D01*
X48339Y285817D01*
X48367Y285831D01*
X48416Y285880D01*
X48429Y285907D01*
X48478Y285956D01*
X48506Y285970D01*
X48554Y286018D01*
X48568Y286046D01*
X48617Y286095D01*
X48644Y286108D01*
X48693Y286157D01*
X48707Y286185D01*
X48741Y286220D01*
X48769Y286233D01*
X48818Y286282D01*
X48832Y286310D01*
X48880Y286358D01*
X48908Y286372D01*
X48956Y286421D01*
X48970Y286448D01*
X49019Y286497D01*
X49047Y286511D01*
X49081Y286545D01*
X49095Y286573D01*
X49144Y286622D01*
X49172Y286635D01*
X49220Y286684D01*
X49234Y286712D01*
X49282Y286760D01*
X49310Y286774D01*
X49359Y286823D01*
X49373Y286850D01*
X49407Y286885D01*
X49435Y286899D01*
X49511Y286961D01*
X49546Y286996D01*
X49615Y287024D01*
X49705Y287059D01*
X49782Y287135D01*
X49809Y287149D01*
X49886Y287211D01*
X49900Y287239D01*
X49976Y287315D01*
X50003Y287329D01*
X50038Y287377D01*
X50101Y287440D01*
X50128Y287454D01*
X50149Y287474D01*
X50163Y287502D01*
X50225Y287565D01*
X50253Y287579D01*
X50274Y287599D01*
X50288Y287627D01*
X50364Y287703D01*
X50392Y287717D01*
X50413Y287738D01*
X50427Y287766D01*
X50489Y287828D01*
X50517Y287842D01*
X50537Y287863D01*
X50551Y287891D01*
X50628Y287967D01*
X50655Y287981D01*
X50690Y288029D01*
X50766Y288106D01*
X50787Y288113D01*
X50801Y288140D01*
X50891Y288230D01*
X50919Y288244D01*
X50940Y288265D01*
X50953Y288293D01*
X51030Y288369D01*
X51058Y288383D01*
X51078Y288404D01*
X51092Y288431D01*
X51168Y288508D01*
X51196Y288522D01*
X51266Y288605D01*
X51307Y288646D01*
X51335Y288660D01*
X51404Y288743D01*
X51432Y288771D01*
X51453Y288778D01*
X51467Y288806D01*
X51557Y288896D01*
X51585Y288910D01*
X51605Y288931D01*
X51619Y288958D01*
X51695Y289035D01*
X51723Y289049D01*
X51744Y289069D01*
X51758Y289097D01*
X51834Y289173D01*
X51862Y289187D01*
X51897Y289236D01*
X51973Y289312D01*
X52000Y289326D01*
X52035Y289374D01*
X52098Y289437D01*
X52118Y289444D01*
X52132Y289471D01*
X52222Y289562D01*
X52250Y289576D01*
X52271Y289596D01*
X52285Y289624D01*
X52361Y289700D01*
X52389Y289714D01*
X52410Y289735D01*
X52424Y289763D01*
X52500Y289839D01*
X52527Y289853D01*
X52562Y289901D01*
X52625Y289964D01*
X52652Y289978D01*
X52673Y289998D01*
X52687Y290026D01*
X52763Y290103D01*
X52791Y290116D01*
X52860Y290200D01*
X52888Y290227D01*
X52916Y290241D01*
X52937Y290262D01*
X52950Y290290D01*
X53027Y290366D01*
X53054Y290380D01*
X53075Y290401D01*
X53089Y290428D01*
X53165Y290505D01*
X53193Y290518D01*
X53228Y290567D01*
X53290Y290630D01*
X53318Y290643D01*
X53339Y290664D01*
X53353Y290692D01*
X53429Y290768D01*
X53457Y290782D01*
X53491Y290831D01*
X53554Y290893D01*
X53581Y290907D01*
X53602Y290928D01*
X53616Y290955D01*
X53678Y291018D01*
X53706Y291032D01*
X53741Y291066D01*
X53755Y291094D01*
X53831Y291170D01*
X53852Y291177D01*
X53866Y291205D01*
X53956Y291295D01*
X53984Y291309D01*
X54004Y291330D01*
X54018Y291357D01*
X54081Y291420D01*
X54108Y291434D01*
X54129Y291455D01*
X54143Y291482D01*
X54219Y291559D01*
X54247Y291572D01*
X54268Y291593D01*
X54282Y291621D01*
X54344Y291683D01*
X54372Y291697D01*
X54407Y291732D01*
X54420Y291760D01*
X54497Y291836D01*
X54524Y291850D01*
X54545Y291871D01*
X54559Y291898D01*
X54635Y291975D01*
X54656Y291982D01*
X54670Y292009D01*
X54746Y292086D01*
X54774Y292099D01*
X54795Y292120D01*
X54809Y292148D01*
X54885Y292224D01*
X54913Y292238D01*
X54934Y292259D01*
X54947Y292287D01*
X55024Y292363D01*
X55051Y292377D01*
X55072Y292398D01*
X55086Y292425D01*
X55149Y292488D01*
X55176Y292502D01*
X55197Y292522D01*
X55211Y292550D01*
X55287Y292626D01*
X55315Y292640D01*
X55336Y292661D01*
X55350Y292689D01*
X55426Y292765D01*
X55454Y292779D01*
X55488Y292827D01*
X55551Y292890D01*
X55578Y292904D01*
X55599Y292925D01*
X55613Y292952D01*
X55689Y293029D01*
X55717Y293043D01*
X55738Y293063D01*
X55752Y293091D01*
X55814Y293153D01*
X55842Y293167D01*
X55863Y293188D01*
X55876Y293216D01*
X55953Y293292D01*
X55981Y293306D01*
X56001Y293327D01*
X56015Y293354D01*
X56091Y293431D01*
X56119Y293445D01*
X56189Y293528D01*
X56216Y293556D01*
X56244Y293570D01*
X56265Y293590D01*
X56279Y293618D01*
X56355Y293694D01*
X56383Y293708D01*
X56403Y293729D01*
X56417Y293757D01*
X56480Y293833D01*
X56515Y293868D01*
X56542Y293937D01*
X56577Y294027D01*
X56632Y294110D01*
X56667Y294187D01*
X56695Y294256D01*
X56729Y294346D01*
X56764Y294464D01*
X56785Y294873D01*
X56799Y295247D01*
X56806Y295365D01*
Y295379D01*
X56799Y312263D01*
X56806Y312464D01*
X56792Y312506D01*
X56778Y312603D01*
X56757Y313040D01*
X56695Y313144D01*
X56681Y313172D01*
X56632Y313234D01*
X56605Y313248D01*
X56542Y313310D01*
X56528Y313338D01*
X56508Y313359D01*
X56480Y313373D01*
X56390Y313463D01*
X56376Y313491D01*
X56327Y313525D01*
X56265Y313588D01*
X56251Y313615D01*
X56230Y313636D01*
X56203Y313650D01*
X56126Y313726D01*
X56112Y313754D01*
X56064Y313789D01*
X56001Y313851D01*
X55988Y313879D01*
X55967Y313900D01*
X55939Y313914D01*
X55863Y313990D01*
X55849Y314018D01*
X55766Y314087D01*
X55724Y314129D01*
X55710Y314156D01*
X55627Y314226D01*
X55599Y314253D01*
X55585Y314281D01*
X55564Y314302D01*
X55537Y314316D01*
X55461Y314392D01*
X55447Y314420D01*
X55398Y314454D01*
X55336Y314517D01*
X55322Y314545D01*
X55301Y314565D01*
X55273Y314579D01*
X55197Y314656D01*
X55183Y314683D01*
X55162Y314704D01*
X55135Y314718D01*
X55058Y314780D01*
X55038Y314801D01*
X55010Y314815D01*
X54941Y314843D01*
X54809Y314891D01*
X54732Y314926D01*
X54642Y314947D01*
X54573Y314961D01*
X54407Y314974D01*
X54150Y314981D01*
D02*
G37*
G36*
X69335Y293680D02*
X62887Y293666D01*
X62824Y293618D01*
X62811Y293563D01*
X62824Y281220D01*
X62859Y281185D01*
X62915Y281172D01*
X64766Y281178D01*
X64953Y281172D01*
X64995Y281185D01*
X65133Y281199D01*
X65515Y281220D01*
X65563Y281241D01*
X65667Y281345D01*
X65681Y281400D01*
X65702Y281823D01*
X65730Y282045D01*
X65723Y282274D01*
X65737Y282316D01*
X65723Y282357D01*
X65730Y282628D01*
X65716Y283571D01*
X65702Y283751D01*
X65688Y283987D01*
X65674Y284153D01*
X65660Y284209D01*
X65633Y284278D01*
X65598Y284396D01*
X65612Y284535D01*
X65723Y284770D01*
X65743Y284958D01*
X65778Y285006D01*
X65855Y285027D01*
X67276Y285020D01*
X67449Y285027D01*
X67491Y285013D01*
X67727Y285027D01*
X67796Y284999D01*
X68191Y284978D01*
X68274Y284923D01*
X68309Y284888D01*
X68337Y284874D01*
X68372Y284840D01*
X68399Y284743D01*
X68455Y284646D01*
X68524Y284576D01*
X68538Y284548D01*
X68600Y284472D01*
X68635Y284438D01*
X68663Y284368D01*
X68677Y284313D01*
X68774Y284160D01*
X68822Y284028D01*
X68857Y283980D01*
X68912Y283924D01*
X68926Y283897D01*
X68989Y283820D01*
X69037Y283772D01*
X69100Y283598D01*
X69134Y283564D01*
X69148Y283536D01*
X69190Y283439D01*
X69224Y283349D01*
X69314Y283259D01*
X69356Y283189D01*
X69426Y283120D01*
X69467Y283023D01*
X69481Y282967D01*
X69550Y282870D01*
X69564Y282843D01*
X69592Y282773D01*
X69626Y282683D01*
X69682Y282600D01*
X69717Y282524D01*
X69751Y282434D01*
X69786Y282385D01*
X69855Y282316D01*
X69897Y282246D01*
X69966Y282177D01*
X70015Y282045D01*
X70084Y281934D01*
X70119Y281844D01*
X70188Y281719D01*
X70244Y281664D01*
X70258Y281636D01*
X70320Y281560D01*
X70355Y281525D01*
X70368Y281497D01*
X70396Y281428D01*
X70410Y281373D01*
X70459Y281310D01*
X70486Y281296D01*
X70514Y281269D01*
X70542Y281255D01*
X70570Y281227D01*
X70667Y281213D01*
X71076Y281192D01*
X71159Y281178D01*
X71360Y281172D01*
X71402Y281185D01*
X71457Y281172D01*
X73537Y281185D01*
X73558Y281206D01*
X73572Y281262D01*
X73558Y281373D01*
X73489Y281470D01*
X73461Y281539D01*
X73426Y281629D01*
X73405Y281650D01*
X73392Y281678D01*
X73336Y281733D01*
X73322Y281761D01*
X73260Y281837D01*
X73211Y281886D01*
X73163Y282017D01*
X73128Y282066D01*
X73087Y282108D01*
X73073Y282135D01*
X73010Y282225D01*
X72990Y282232D01*
X72983Y282253D01*
X72962Y282260D01*
X72948Y282288D01*
X72920Y282357D01*
X72885Y282447D01*
X72865Y282468D01*
X72851Y282496D01*
X72823Y282524D01*
X72761Y282697D01*
X72684Y282773D01*
X72670Y282801D01*
X72573Y282926D01*
X72546Y282954D01*
X72518Y283023D01*
X72504Y283078D01*
X72407Y283231D01*
X72358Y283363D01*
X72324Y283411D01*
X72296Y283425D01*
X72282Y283453D01*
X72255Y283481D01*
X72213Y283550D01*
X72144Y283619D01*
X72095Y283751D01*
X72026Y283862D01*
X71991Y283952D01*
X71963Y284021D01*
X71901Y284098D01*
X71866Y284132D01*
X71825Y284202D01*
X71755Y284271D01*
X71727Y284340D01*
X71693Y284431D01*
X71658Y284479D01*
X71603Y284562D01*
X71582Y284639D01*
X71554Y284708D01*
X71492Y284826D01*
X71464Y284923D01*
X71478Y285200D01*
X71547Y285297D01*
X71575Y285325D01*
X71617Y285394D01*
X71651Y285429D01*
X71672Y285436D01*
X71679Y285443D01*
X71714Y285478D01*
X71727Y285505D01*
X71790Y285568D01*
X71818Y285582D01*
X71852Y285616D01*
X71866Y285644D01*
X71929Y285706D01*
X71956Y285720D01*
X71977Y285741D01*
X71991Y285769D01*
X72053Y285831D01*
X72081Y285845D01*
X72116Y285880D01*
X72130Y285907D01*
X72192Y285970D01*
X72220Y285984D01*
X72241Y286005D01*
X72255Y286032D01*
X72317Y286095D01*
X72345Y286108D01*
X72379Y286143D01*
X72393Y286171D01*
X72456Y286233D01*
X72483Y286247D01*
X72518Y286282D01*
X72532Y286310D01*
X72594Y286372D01*
X72622Y286386D01*
X72643Y286407D01*
X72657Y286434D01*
X72719Y286497D01*
X72747Y286511D01*
X72782Y286545D01*
X72795Y286573D01*
X72858Y286635D01*
X72885Y286649D01*
X72920Y286684D01*
X72934Y286712D01*
X72983Y286760D01*
X73010Y286774D01*
X73059Y286823D01*
X73073Y286850D01*
X73135Y286927D01*
X73156Y286948D01*
X73184Y287017D01*
X73197Y287072D01*
X73253Y287197D01*
X73267Y287253D01*
X73288Y287579D01*
X73309Y287988D01*
X73315Y288522D01*
X73309Y288528D01*
X73322Y288570D01*
X73315Y290310D01*
X73322Y290415D01*
X73309Y290456D01*
X73295Y291261D01*
X73281Y291302D01*
X73260Y291628D01*
X73197Y291774D01*
X73163Y291864D01*
X73114Y291940D01*
X73073Y291982D01*
X73059Y292009D01*
X72983Y292086D01*
X72955Y292099D01*
X72934Y292120D01*
X72920Y292148D01*
X72844Y292224D01*
X72816Y292238D01*
X72795Y292259D01*
X72782Y292287D01*
X72566Y292502D01*
X72546Y292509D01*
X72532Y292536D01*
X72442Y292626D01*
X72414Y292640D01*
X72379Y292689D01*
X72317Y292751D01*
X72289Y292765D01*
X72268Y292786D01*
X72255Y292814D01*
X72178Y292890D01*
X72151Y292904D01*
X72130Y292925D01*
X72116Y292952D01*
X71915Y293153D01*
X71887Y293167D01*
X71866Y293188D01*
X71852Y293216D01*
X71776Y293292D01*
X71748Y293306D01*
X71679Y293389D01*
X71651Y293417D01*
X71624Y293431D01*
X71554Y293500D01*
X71526Y293514D01*
X71429Y293556D01*
X71339Y293590D01*
X71270Y293618D01*
X71187Y293632D01*
X70882Y293646D01*
X70472Y293666D01*
X69335Y293680D01*
D02*
G37*
G36*
X33140Y293666D02*
X33029Y293653D01*
X33008Y293632D01*
X32981Y293563D01*
X33001Y292626D01*
X33015Y292335D01*
X33029Y292099D01*
X33043Y291989D01*
X33057Y291933D01*
X33071Y291864D01*
X33085Y291780D01*
X33105Y291593D01*
X33119Y291496D01*
X33133Y291274D01*
X33168Y291073D01*
X33189Y290997D01*
X33244Y290775D01*
X33258Y290636D01*
X33272Y290484D01*
X33300Y290415D01*
X33341Y290262D01*
X33355Y290207D01*
X33383Y290040D01*
X33404Y289867D01*
X33418Y289797D01*
X33431Y289742D01*
X33480Y289583D01*
X33494Y289527D01*
X33521Y289333D01*
X33542Y289173D01*
X33556Y289104D01*
X33598Y288993D01*
X33619Y288917D01*
X33646Y288806D01*
X33660Y288667D01*
X33681Y288577D01*
X33730Y288459D01*
X33771Y288362D01*
X33785Y288265D01*
X33799Y288209D01*
X33834Y288119D01*
X33896Y287974D01*
X33924Y287877D01*
X33938Y287780D01*
X34021Y287599D01*
X34049Y287502D01*
X34076Y287377D01*
X34146Y287225D01*
X34173Y287128D01*
X34187Y287072D01*
X34208Y286982D01*
X34277Y286830D01*
X34298Y286767D01*
X34326Y286656D01*
X34340Y286573D01*
X34409Y286462D01*
X34444Y286372D01*
X34513Y286220D01*
X34576Y286074D01*
X34596Y285956D01*
X34631Y285866D01*
X34728Y285658D01*
X34839Y285422D01*
X34853Y285325D01*
X34874Y285249D01*
X34936Y285131D01*
X34978Y285034D01*
X35657Y283661D01*
X35699Y283591D01*
X35768Y283522D01*
X35782Y283494D01*
X35844Y283418D01*
X35865Y283397D01*
X35879Y283370D01*
X35935Y283245D01*
X35990Y283148D01*
X36059Y282995D01*
X36129Y282870D01*
X36184Y282746D01*
X36240Y282649D01*
X36309Y282579D01*
X36323Y282551D01*
X36385Y282475D01*
X36420Y282440D01*
X36448Y282371D01*
X36462Y282316D01*
X36559Y282163D01*
X36572Y282108D01*
X36642Y281983D01*
X36697Y281927D01*
X36711Y281900D01*
X36878Y281733D01*
X36891Y281705D01*
X36933Y281664D01*
X36947Y281636D01*
X36975Y281567D01*
X37044Y281442D01*
X37113Y281373D01*
X37127Y281345D01*
X37169Y281303D01*
X37183Y281276D01*
X37224Y281234D01*
X37273Y281102D01*
X37342Y281019D01*
X37377Y280970D01*
X37405Y280943D01*
X37411Y280922D01*
X37439Y280908D01*
X37529Y280818D01*
X37543Y280790D01*
X37599Y280735D01*
X37613Y280707D01*
X37654Y280610D01*
X37668Y280568D01*
X37731Y280492D01*
X37765Y280457D01*
X37779Y280430D01*
X38084Y280125D01*
X38098Y280097D01*
X38140Y280055D01*
X38153Y280028D01*
X38209Y279889D01*
X38278Y279820D01*
X38292Y279792D01*
X38354Y279715D01*
X38431Y279653D01*
X38493Y279577D01*
X38570Y279514D01*
X38583Y279487D01*
X38632Y279438D01*
X38660Y279424D01*
X38722Y279362D01*
X38736Y279334D01*
X38757Y279313D01*
X38784Y279299D01*
X40580Y277504D01*
X40594Y277476D01*
X40615Y277455D01*
X40643Y277441D01*
X40705Y277379D01*
X40719Y277351D01*
X40767Y277302D01*
X40795Y277289D01*
X40830Y277254D01*
X40844Y277226D01*
X40906Y277164D01*
X40934Y277150D01*
X40969Y277115D01*
X40982Y277087D01*
X41031Y277039D01*
X41059Y277025D01*
X41107Y276977D01*
X41121Y276949D01*
X41156Y276914D01*
X41184Y276900D01*
X41211Y276873D01*
X41239Y276859D01*
X41294Y276803D01*
X41364Y276775D01*
X41419Y276762D01*
X41447Y276734D01*
X41475Y276720D01*
X41502Y276692D01*
X41530Y276678D01*
X41711Y276498D01*
X41738Y276484D01*
X41808Y276415D01*
X41835Y276401D01*
X41905Y276373D01*
X41960Y276359D01*
X41988Y276332D01*
X42016Y276318D01*
X42071Y276262D01*
X42099Y276248D01*
X42203Y276145D01*
X42210Y276124D01*
X42238Y276110D01*
X42314Y276047D01*
X42362Y275999D01*
X42439Y275978D01*
X42508Y275950D01*
X42543Y275916D01*
X42570Y275902D01*
X42626Y275846D01*
X42654Y275833D01*
X42709Y275777D01*
X42737Y275763D01*
X42765Y275735D01*
X42834Y275708D01*
X42924Y275673D01*
X42972Y275624D01*
X43000Y275611D01*
X43180Y275430D01*
X43208Y275416D01*
X43278Y275347D01*
X43375Y275306D01*
X43430Y275292D01*
X43527Y275222D01*
X43597Y275194D01*
X43687Y275160D01*
X43770Y275091D01*
X43791Y275070D01*
X43818Y275056D01*
X43895Y274993D01*
X43929Y274959D01*
X43957Y274945D01*
X44054Y274903D01*
X44207Y274820D01*
X44332Y274765D01*
X44456Y274695D01*
X44553Y274654D01*
X44678Y274584D01*
X44734Y274529D01*
X44762Y274515D01*
X44838Y274453D01*
X44886Y274404D01*
X44976Y274369D01*
X45046Y274342D01*
X45150Y274279D01*
X45219Y274251D01*
X46370Y273683D01*
X46578Y273586D01*
X46703Y273572D01*
X46994Y273433D01*
X47202Y273336D01*
X47258Y273322D01*
X47403Y273288D01*
X47715Y273142D01*
X47896Y273059D01*
X48014Y273038D01*
X48069Y273024D01*
X48145Y272990D01*
X48173Y272976D01*
X48270Y272934D01*
X48464Y272892D01*
X48617Y272823D01*
X48755Y272782D01*
X48839Y272768D01*
X48908Y272740D01*
X49061Y272671D01*
X49116Y272657D01*
X49213Y272643D01*
X49282Y272615D01*
X49435Y272546D01*
X49546Y272518D01*
X49650Y272497D01*
X49837Y272421D01*
X49948Y272393D01*
X50107Y272372D01*
X50219Y272345D01*
X50288Y272317D01*
X50406Y272282D01*
X50600Y272255D01*
X50732Y272234D01*
X50842Y272220D01*
X50898Y272206D01*
X50988Y272171D01*
X51078Y272150D01*
X51148Y272137D01*
X51231Y272123D01*
X51342Y272109D01*
X51522Y272081D01*
X51578Y272067D01*
X51668Y272033D01*
X51758Y272012D01*
X51827Y271998D01*
X51980Y271984D01*
X52132Y271956D01*
X52188Y271943D01*
X52257Y271929D01*
X52333Y271908D01*
X52444Y271880D01*
X52583Y271866D01*
X52826Y271845D01*
X52950Y271832D01*
X53131Y271804D01*
X53269Y271776D01*
X53394Y271762D01*
X53699Y271748D01*
X53880Y271735D01*
X54642Y271721D01*
X56965Y271714D01*
X57007Y271728D01*
X57922Y271741D01*
X57964Y271755D01*
X58352Y271769D01*
X58394Y271783D01*
X58484Y271804D01*
X58768Y271838D01*
X58865Y271852D01*
X59045Y271866D01*
X59212Y271880D01*
X59253Y271894D01*
X59309Y271908D01*
X59406Y271936D01*
X59482Y271956D01*
X59552Y271970D01*
X59739Y271991D01*
X59871Y272012D01*
X59926Y272026D01*
X60002Y272047D01*
X60072Y272074D01*
X60169Y272088D01*
X60224Y272102D01*
X60398Y272123D01*
X60481Y272137D01*
X60550Y272150D01*
X60661Y272178D01*
X60779Y272213D01*
X60834Y272227D01*
X61028Y272255D01*
X61188Y272275D01*
X61257Y272289D01*
X61327Y272317D01*
X61486Y272365D01*
X61542Y272379D01*
X61715Y272400D01*
X61770Y272414D01*
X61881Y272456D01*
X61999Y272504D01*
X62193Y272546D01*
X62346Y272615D01*
X62415Y272643D01*
X62512Y272657D01*
X62568Y272671D01*
X62720Y272740D01*
X62790Y272768D01*
X62949Y272802D01*
X63060Y272844D01*
X63136Y272879D01*
X63206Y272906D01*
X63324Y272927D01*
X63379Y272941D01*
X63518Y273010D01*
X63573Y273024D01*
X63650Y273045D01*
X63795Y273080D01*
X63899Y273142D01*
X63989Y273177D01*
X64065Y273211D01*
X64274Y273309D01*
X64412Y273322D01*
X64537Y273392D01*
X64662Y273447D01*
X64731Y273475D01*
X64939Y273572D01*
X65036Y273586D01*
X65113Y273607D01*
X65258Y273683D01*
X65328Y273711D01*
X66035Y274071D01*
X66132Y274113D01*
X66312Y274210D01*
X66409Y274251D01*
X66562Y274335D01*
X66659Y274376D01*
X66784Y274446D01*
X66853Y274515D01*
X66922Y274557D01*
X66978Y274612D01*
X67075Y274654D01*
X67144Y274681D01*
X67227Y274737D01*
X67325Y274778D01*
X67394Y274806D01*
X67470Y274869D01*
X67491Y274889D01*
X67519Y274903D01*
X67546Y274931D01*
X67574Y274945D01*
X67643Y275014D01*
X67782Y275070D01*
X67810Y275084D01*
X67921Y275153D01*
X68053Y275201D01*
X68163Y275271D01*
X68240Y275306D01*
X68330Y275340D01*
X68351Y275361D01*
X68378Y275375D01*
X68448Y275444D01*
X68475Y275458D01*
X68656Y275638D01*
X68684Y275652D01*
X68711Y275680D01*
X68781Y275708D01*
X68871Y275742D01*
X68947Y275819D01*
X68975Y275833D01*
X69100Y275930D01*
X69127Y275957D01*
X69259Y276006D01*
X69308Y276040D01*
X69363Y276096D01*
X69391Y276110D01*
X69557Y276276D01*
X69585Y276290D01*
X69640Y276346D01*
X69710Y276373D01*
X69800Y276408D01*
X69821Y276429D01*
X69848Y276443D01*
X69918Y276512D01*
X69946Y276526D01*
X70036Y276616D01*
X70050Y276644D01*
X70098Y276678D01*
X70133Y276713D01*
X70147Y276741D01*
X70181Y276775D01*
X70209Y276789D01*
X70251Y276831D01*
X70278Y276845D01*
X70320Y276886D01*
X70472Y276942D01*
X70542Y277011D01*
X70570Y277025D01*
X70646Y277087D01*
X70660Y277115D01*
X70722Y277178D01*
X70750Y277192D01*
X70785Y277226D01*
X70798Y277254D01*
X70861Y277316D01*
X70889Y277330D01*
X70909Y277351D01*
X70923Y277379D01*
X70999Y277455D01*
X71027Y277469D01*
X71069Y277511D01*
X71097Y277524D01*
X71124Y277552D01*
X71256Y277601D01*
X71305Y277635D01*
X71360Y277691D01*
X71388Y277705D01*
X71464Y277781D01*
X71478Y277809D01*
X71547Y277878D01*
X71561Y277906D01*
X71589Y277975D01*
X71603Y278030D01*
X71665Y278107D01*
X71762Y278204D01*
X71831Y278232D01*
X71922Y278266D01*
X71970Y278301D01*
X72026Y278356D01*
X72053Y278370D01*
X72130Y278447D01*
X72144Y278474D01*
X72227Y278557D01*
X72255Y278668D01*
X72296Y278738D01*
X72317Y278759D01*
X72372Y278772D01*
X72449Y278793D01*
X72470Y278814D01*
X72497Y278828D01*
X72553Y278883D01*
X72580Y278897D01*
X72670Y278987D01*
X72684Y279015D01*
X72754Y279084D01*
X72782Y279154D01*
X72816Y279244D01*
X72865Y279334D01*
X72851Y279390D01*
X72788Y279410D01*
X72705Y279396D01*
X72650Y279341D01*
X72622Y279327D01*
X72594Y279299D01*
X72566Y279286D01*
X72532Y279251D01*
X72518Y279223D01*
X72456Y279161D01*
X72428Y279147D01*
X72393Y279112D01*
X72379Y279084D01*
X72303Y279008D01*
X72275Y278994D01*
X72255Y278974D01*
X72241Y278946D01*
X72053Y278759D01*
X72033Y278752D01*
X72019Y278724D01*
X71929Y278634D01*
X71901Y278620D01*
X71866Y278585D01*
X71852Y278557D01*
X71776Y278481D01*
X71748Y278467D01*
X71727Y278447D01*
X71714Y278419D01*
X71402Y278107D01*
X71374Y278093D01*
X71339Y278058D01*
X71325Y278030D01*
X71263Y277968D01*
X71235Y277954D01*
X71200Y277920D01*
X71187Y277892D01*
X71124Y277829D01*
X71097Y277816D01*
X71069Y277788D01*
X71041Y277774D01*
X70986Y277719D01*
X70889Y277691D01*
X70819Y277649D01*
X70750Y277580D01*
X70722Y277566D01*
X70674Y277531D01*
X70660Y277504D01*
X70105Y276949D01*
X70098Y276928D01*
X70070Y276914D01*
X70029Y276873D01*
X70001Y276859D01*
X69946Y276803D01*
X69918Y276789D01*
X69848Y276762D01*
X69793Y276748D01*
X69751Y276706D01*
X69731Y276699D01*
X69724Y276678D01*
X69696Y276665D01*
X69668Y276637D01*
X69640Y276623D01*
X69578Y276560D01*
X69564Y276533D01*
X69530Y276498D01*
X69502Y276484D01*
X69446Y276429D01*
X69419Y276415D01*
X69391Y276387D01*
X69335Y276373D01*
X69245Y276339D01*
X69169Y276262D01*
X69141Y276248D01*
X69065Y276186D01*
X69030Y276151D01*
X69002Y276138D01*
X68905Y276096D01*
X68808Y276040D01*
X68739Y275971D01*
X68711Y275957D01*
X68531Y275777D01*
X68503Y275763D01*
X68475Y275735D01*
X68406Y275708D01*
X68316Y275673D01*
X68240Y275597D01*
X68212Y275583D01*
X68136Y275520D01*
X68115Y275500D01*
X68087Y275486D01*
X68060Y275458D01*
X67928Y275410D01*
X67879Y275375D01*
X67838Y275333D01*
X67810Y275319D01*
X67782Y275292D01*
X67754Y275278D01*
X67685Y275208D01*
X67657Y275194D01*
X67560Y275153D01*
X67297Y275028D01*
X67200Y274973D01*
X66770Y274765D01*
X66700Y274723D01*
X66645Y274668D01*
X66617Y274654D01*
X66589Y274626D01*
X66562Y274612D01*
X66520Y274571D01*
X66492Y274557D01*
X66465Y274529D01*
X66375Y274494D01*
X66305Y274466D01*
X66215Y274404D01*
X66146Y274376D01*
X66056Y274342D01*
X65972Y274286D01*
X65896Y274251D01*
X65806Y274217D01*
X65695Y274147D01*
X65619Y274113D01*
X65549Y274085D01*
X65425Y274016D01*
X65300Y273960D01*
X65064Y273849D01*
X64932Y273829D01*
X64863Y273801D01*
X64502Y273620D01*
X64329Y273544D01*
X64121Y273447D01*
X63996Y273433D01*
X63816Y273350D01*
X63747Y273322D01*
X63650Y273309D01*
X63476Y273246D01*
X63330Y273184D01*
X63233Y273170D01*
X63178Y273156D01*
X62984Y273073D01*
X62915Y273045D01*
X62783Y273024D01*
X62713Y272997D01*
X62540Y272920D01*
X62325Y272872D01*
X62263Y272837D01*
X62193Y272809D01*
X62096Y272782D01*
X62041Y272768D01*
X61965Y272747D01*
X61895Y272719D01*
X61819Y272698D01*
X61812Y272691D01*
X61736Y272671D01*
X61680Y272657D01*
X61500Y272643D01*
X61445Y272629D01*
X61313Y272608D01*
X61257Y272594D01*
X61188Y272567D01*
X61070Y272532D01*
X61015Y272518D01*
X60918Y272504D01*
X60786Y272483D01*
X60633Y272428D01*
X60557Y272407D01*
X60446Y272379D01*
X60245Y272345D01*
X60189Y272331D01*
X60120Y272303D01*
X60065Y272289D01*
X59981Y272275D01*
X59871Y272262D01*
X59787Y272248D01*
X59662Y272234D01*
X59385Y272192D01*
X59309Y272171D01*
X59212Y272157D01*
X59156Y272144D01*
X58907Y272130D01*
X58865Y272116D01*
X58401Y272095D01*
X58262Y272081D01*
X58137Y272067D01*
X58054Y272054D01*
X57984Y272040D01*
X57874Y272026D01*
X57707Y272012D01*
X57485Y271998D01*
X57000Y271984D01*
X56882Y271977D01*
X56840Y271991D01*
X56494Y271977D01*
X54712Y271984D01*
X54663Y271977D01*
X54622Y271991D01*
X54580Y271977D01*
X54358Y271991D01*
X53970Y272005D01*
X53928Y272019D01*
X53651Y272033D01*
X53609Y272047D01*
X53512Y272060D01*
X53457Y272074D01*
X53235Y272088D01*
X53006Y272109D01*
X52729Y272123D01*
X52618Y272137D01*
X52437Y272150D01*
X52285Y272178D01*
X52208Y272199D01*
X51876Y272241D01*
X51585Y272282D01*
X51529Y272296D01*
X51432Y272324D01*
X51321Y272352D01*
X51189Y272372D01*
X51002Y272393D01*
X50856Y272428D01*
X50780Y272463D01*
X50641Y272504D01*
X50551Y272525D01*
X50496Y272539D01*
X50420Y272574D01*
X50350Y272601D01*
X50184Y272629D01*
X50045Y272643D01*
X49948Y272657D01*
X49858Y272677D01*
X49705Y272733D01*
X49587Y272768D01*
X49497Y272789D01*
X49442Y272802D01*
X49366Y272837D01*
X49241Y272892D01*
X49109Y272913D01*
X48998Y272955D01*
X48853Y273017D01*
X48797Y273031D01*
X48651Y273066D01*
X48499Y273135D01*
X48381Y273170D01*
X48277Y273191D01*
X48208Y273218D01*
X48062Y273281D01*
X47951Y273309D01*
X47868Y273322D01*
X47549Y273475D01*
X47369Y273558D01*
X47272Y273572D01*
X47216Y273586D01*
X46953Y273711D01*
X46883Y273738D01*
X46703Y273822D01*
X46648Y273836D01*
X46543Y273856D01*
X46474Y273884D01*
X46370Y273946D01*
X46280Y273981D01*
X46211Y274009D01*
X46127Y274064D01*
X46058Y274092D01*
X45906Y274161D01*
X45885Y274182D01*
X45857Y274196D01*
X45732Y274251D01*
X45607Y274321D01*
X45483Y274376D01*
X45330Y274459D01*
X45205Y274515D01*
X45136Y274557D01*
X45060Y274619D01*
X44997Y274668D01*
X44970Y274681D01*
X44900Y274751D01*
X44824Y274772D01*
X44741Y274813D01*
X44637Y274876D01*
X44567Y274903D01*
X44248Y275056D01*
X44221Y275070D01*
X44193Y275098D01*
X44165Y275111D01*
X44110Y275167D01*
X44082Y275181D01*
X44006Y275243D01*
X43971Y275278D01*
X43902Y275306D01*
X43846Y275319D01*
X43770Y275382D01*
X43735Y275416D01*
X43707Y275430D01*
X43631Y275493D01*
X43597Y275527D01*
X43569Y275541D01*
X43430Y275597D01*
X43402Y275611D01*
X43305Y275680D01*
X43250Y275694D01*
X43125Y275763D01*
X43049Y275826D01*
X43000Y275860D01*
X42945Y275916D01*
X42917Y275930D01*
X42792Y275985D01*
X42765Y275999D01*
X42688Y276061D01*
X42640Y276096D01*
X42473Y276262D01*
X42446Y276276D01*
X42376Y276346D01*
X42279Y276373D01*
X42182Y276429D01*
X42127Y276484D01*
X42099Y276498D01*
X42023Y276574D01*
X42009Y276602D01*
X41988Y276623D01*
X41960Y276637D01*
X41932Y276665D01*
X41905Y276678D01*
X41835Y276748D01*
X41738Y276775D01*
X41669Y276817D01*
X41627Y276859D01*
X41600Y276873D01*
X41572Y276900D01*
X41544Y276914D01*
X41523Y276935D01*
X41509Y276963D01*
X41281Y277192D01*
X41260Y277199D01*
X41246Y277226D01*
X40892Y277580D01*
X40865Y277594D01*
X40795Y277663D01*
X40767Y277677D01*
X40726Y277691D01*
X40636Y277725D01*
X40553Y277795D01*
X40504Y277829D01*
X39069Y279265D01*
X39055Y279293D01*
X38999Y279348D01*
X38972Y279417D01*
X38951Y279494D01*
X38930Y279514D01*
X38916Y279542D01*
X38847Y279611D01*
X38833Y279639D01*
X38479Y279993D01*
X38458Y280000D01*
X38445Y280028D01*
X38257Y280215D01*
X38230Y280229D01*
X38167Y280291D01*
X38153Y280319D01*
X38126Y280347D01*
X38112Y280374D01*
X38070Y280416D01*
X38056Y280443D01*
X38029Y280513D01*
X38015Y280568D01*
X37931Y280652D01*
X37918Y280679D01*
X37855Y280756D01*
X37827Y280769D01*
X37751Y280846D01*
X37737Y280873D01*
X37682Y280929D01*
X37668Y280957D01*
X37640Y281026D01*
X37606Y281116D01*
X37529Y281192D01*
X37515Y281220D01*
X37335Y281400D01*
X37321Y281428D01*
X37280Y281470D01*
X37266Y281497D01*
X37238Y281567D01*
X37183Y281664D01*
X37141Y281705D01*
X37127Y281733D01*
X37099Y281761D01*
X37086Y281789D01*
X37016Y281858D01*
X37002Y281886D01*
X36975Y281955D01*
X36940Y282045D01*
X36905Y282094D01*
X36850Y282177D01*
X36829Y282253D01*
X36808Y282302D01*
X36746Y282378D01*
X36711Y282413D01*
X36697Y282440D01*
X36670Y282468D01*
X36656Y282496D01*
X36600Y282551D01*
X36572Y282621D01*
X36559Y282676D01*
X36496Y282752D01*
X36462Y282787D01*
X36448Y282815D01*
X36385Y282891D01*
X36365Y282912D01*
X36351Y282940D01*
X36323Y282967D01*
X36309Y283023D01*
X36073Y283481D01*
X36032Y283578D01*
X35976Y283675D01*
X35921Y283730D01*
X35907Y283758D01*
X35844Y283834D01*
X35824Y283855D01*
X35810Y283883D01*
X35754Y284008D01*
X35699Y284105D01*
X35629Y284257D01*
X35560Y284382D01*
X35491Y284535D01*
X35435Y284632D01*
X35352Y284812D01*
X35338Y284840D01*
X35269Y284951D01*
X35241Y285020D01*
X35206Y285110D01*
X35130Y285256D01*
X35116Y285311D01*
X35082Y285471D01*
X35005Y285616D01*
X34978Y285686D01*
X34853Y285949D01*
X34839Y286046D01*
X34825Y286102D01*
X34790Y286192D01*
X34770Y286213D01*
X34728Y286310D01*
X34700Y286379D01*
X34589Y286615D01*
X34576Y286670D01*
X34555Y286774D01*
X34527Y286843D01*
X34451Y287031D01*
X34437Y287128D01*
X34388Y287260D01*
X34354Y287336D01*
X34326Y287405D01*
X34312Y287461D01*
X34277Y287606D01*
X34250Y287676D01*
X34215Y287752D01*
X34187Y287821D01*
X34173Y287877D01*
X34160Y287974D01*
X34090Y288126D01*
X34062Y288196D01*
X34049Y288251D01*
X34014Y288397D01*
X33986Y288466D01*
X33965Y288528D01*
X33938Y288626D01*
X33924Y288681D01*
X33910Y288861D01*
X33896Y288917D01*
X33875Y289049D01*
X33861Y289104D01*
X33834Y289173D01*
X33785Y289333D01*
X33771Y289471D01*
X33757Y289527D01*
X33743Y289610D01*
X33702Y289707D01*
X33660Y289874D01*
X33646Y289971D01*
X33633Y290151D01*
X33619Y290207D01*
X33598Y290283D01*
X33563Y290401D01*
X33521Y290567D01*
X33487Y290851D01*
X33431Y291073D01*
X33411Y291261D01*
X33390Y291475D01*
X33376Y291739D01*
X33362Y291864D01*
X33348Y292113D01*
X33334Y292224D01*
X33321Y292307D01*
X33307Y292363D01*
X33293Y292474D01*
X33279Y292710D01*
X33265Y292890D01*
X33251Y293140D01*
X33237Y293583D01*
X33217Y293632D01*
X33196Y293653D01*
X33140Y293666D01*
D02*
G37*
%LPD*%
G36*
X82801Y291004D02*
X82898Y290948D01*
X83023Y290893D01*
X83099Y290872D01*
X83148Y290837D01*
X83168Y290775D01*
X83162Y284639D01*
X83168Y284493D01*
X83155Y284451D01*
X83141Y284396D01*
X83134Y284139D01*
X83141Y284091D01*
X83113Y284008D01*
X82981Y283876D01*
X82884Y283862D01*
X82537Y283848D01*
X82496Y283834D01*
X82427Y283820D01*
X82385Y283834D01*
X82274Y283848D01*
X82232Y283834D01*
X82135Y283820D01*
X82094Y283834D01*
X81851Y283827D01*
X81678Y283834D01*
X81636Y283820D01*
X81428Y283834D01*
X81386Y283820D01*
X78446Y283834D01*
X78384Y283897D01*
X78377Y284042D01*
X78384Y284105D01*
X78370Y284118D01*
X78384Y284160D01*
Y284216D01*
Y284230D01*
X78377Y289146D01*
X78391Y290116D01*
X78398Y290165D01*
X78384Y290207D01*
X78405Y290602D01*
X78419Y290782D01*
X78440Y290831D01*
X78509Y290928D01*
X78523Y290955D01*
X78558Y290990D01*
X78654Y291004D01*
X78745Y290983D01*
X78863Y290935D01*
X79188Y290914D01*
X79459Y290893D01*
X79500Y290879D01*
X79681Y290893D01*
X79847Y290879D01*
X79889Y290893D01*
X80138Y290879D01*
X80180Y290893D01*
X80402Y290879D01*
X81865Y290900D01*
X82267Y290928D01*
X82447Y290942D01*
X82503Y290955D01*
X82621Y291004D01*
X82676Y291018D01*
X82801Y291004D01*
D02*
G37*
G36*
X69211Y291143D02*
X69412Y291150D01*
X69481Y291136D01*
X69543Y291129D01*
X69585Y291143D01*
X69675Y291150D01*
X69744Y291136D01*
X69800Y291122D01*
X70160Y291108D01*
X70230Y291080D01*
X70313Y290997D01*
X70327Y290969D01*
X70355Y290900D01*
X70375Y290532D01*
X70389Y290463D01*
X70396Y290387D01*
X70382Y290345D01*
X70389Y290103D01*
X70382Y289929D01*
X70396Y289888D01*
X70382Y289707D01*
X70396Y289569D01*
X70389Y288757D01*
X70396Y288653D01*
X70382Y288612D01*
X70389Y288397D01*
X70382Y288196D01*
X70396Y288154D01*
X70375Y288036D01*
X70361Y287814D01*
X70348Y287648D01*
X70327Y287599D01*
X70265Y287523D01*
X70237Y287495D01*
X70209Y287481D01*
X70167Y287468D01*
X70070Y287454D01*
X70043Y287468D01*
X70001Y287454D01*
X69751Y287440D01*
X69710Y287426D01*
X69481Y287433D01*
X66382Y287426D01*
X66340Y287440D01*
X66298D01*
X66291Y287433D01*
X66118Y287426D01*
X66049Y287454D01*
X65792Y287461D01*
X65716Y287454D01*
X65674Y287468D01*
X65647Y287481D01*
X65570Y287544D01*
X65529Y287586D01*
X65501Y287655D01*
X65487Y288043D01*
X65473Y288085D01*
X65459Y288182D01*
X65473Y288223D01*
X65487Y288307D01*
X65473Y288348D01*
X65459Y288445D01*
X65473Y288501D01*
X65466Y288743D01*
X65473Y288903D01*
X65459Y288944D01*
X65466Y289132D01*
X65459Y290886D01*
X65487Y290969D01*
X65522Y291004D01*
X65577Y291018D01*
X65653Y291039D01*
X65723Y291066D01*
X65799Y291101D01*
X65938Y291115D01*
X66527Y291136D01*
X67359Y291150D01*
X68614Y291157D01*
X68656Y291143D01*
X68885Y291150D01*
X69072Y291143D01*
X69113Y291157D01*
X69211Y291143D01*
D02*
G37*
D12*
X315250Y379249D02*
G03*
X315611Y379100I361J361D01*
G01*
X315162Y203473D02*
Y259249D01*
X213750Y275061D02*
Y327356D01*
X220968Y338729D02*
Y339000D01*
X214042Y331803D02*
X220968Y338729D01*
X214042Y327648D02*
Y331803D01*
X213750Y327356D02*
X214042Y327648D01*
X315250Y379249D02*
Y392363D01*
X315611Y379100D02*
X346750D01*
X213500Y274811D02*
X213750Y275061D01*
D16*
X331693Y84089D02*
D03*
D17*
X230693Y58689D02*
D03*
Y84089D02*
D03*
Y109489D02*
D03*
D18*
X145500Y88750D02*
D03*
Y56750D02*
D03*
D19*
X308750Y489250D02*
D03*
X316750D02*
D03*
X343250Y488750D02*
D03*
X335250D02*
D03*
X112250Y463508D02*
D03*
X104250D02*
D03*
X123750D02*
D03*
X131750D02*
D03*
D20*
X301250Y464000D02*
D03*
Y438600D02*
D03*
X358750Y464000D02*
D03*
Y438600D02*
D03*
D21*
X342700Y470050D02*
D03*
X330000D02*
D03*
X317300D02*
D03*
X342700Y432550D02*
D03*
X330000D02*
D03*
X317300D02*
D03*
D22*
X273500Y274811D02*
D03*
Y226811D02*
D03*
X258500Y226811D02*
D03*
X243500Y226811D02*
D03*
X228500D02*
D03*
X258500Y274811D02*
D03*
X243500Y274811D02*
D03*
X213500D02*
D03*
X228500Y274811D02*
D03*
D23*
X213500Y229311D02*
D03*
D24*
X34250Y104750D02*
D03*
Y133750D02*
D03*
D25*
X457000Y412076D02*
D03*
Y421676D02*
D03*
D26*
X466849Y435727D02*
D03*
X473649D02*
D03*
D27*
X167947Y257371D02*
D03*
Y333571D02*
D03*
X167947Y384471D02*
D03*
X401947D02*
D03*
Y206471D02*
D03*
X401947Y295471D02*
D03*
X167947Y206471D02*
D03*
D28*
X315250Y259250D02*
D03*
X315250Y319250D02*
D03*
X355250D02*
D03*
X355250Y259250D02*
D03*
X282750Y379249D02*
D03*
X282750Y319250D02*
D03*
X315250Y319250D02*
D03*
X315250Y379249D02*
D03*
D29*
X72000Y147450D02*
D03*
Y118250D02*
D03*
X109500Y147450D02*
D03*
Y118250D02*
D03*
X144750Y119650D02*
D03*
X144750Y148850D02*
D03*
D30*
X192250Y38250D02*
D03*
Y56250D02*
D03*
D31*
X315000Y218811D02*
D03*
X331000Y218811D02*
D03*
X213500Y309061D02*
D03*
X229500D02*
D03*
D32*
X271250Y448300D02*
D03*
Y464300D02*
D03*
D33*
X285250Y464250D02*
D03*
Y455050D02*
D03*
X168750Y42690D02*
D03*
Y51890D02*
D03*
X431167Y384149D02*
D03*
X431167Y374949D02*
D03*
X346750Y379100D02*
D03*
Y369900D02*
D03*
D34*
X34250Y237000D02*
D03*
X52250D02*
D03*
X34250Y211750D02*
D03*
X52250D02*
D03*
D35*
X213500Y295561D02*
D03*
X222700D02*
D03*
X315226Y232063D02*
D03*
X324426Y232063D02*
D03*
D36*
X213500Y196772D02*
D03*
X223100D02*
D03*
X447400Y435726D02*
D03*
X457000Y435727D02*
D03*
D37*
X293462Y298212D02*
D03*
X300250Y305000D02*
D03*
D38*
X240792Y457200D02*
D03*
Y464000D02*
D03*
D68*
X427153Y426000D02*
G03*
X445113Y433439I0J25400D01*
G01*
X384021Y426000D02*
G03*
X366060Y418560I0J-25400D01*
G01*
X358154Y415250D02*
G03*
X366000Y418500I0J11096D01*
G01*
X275771Y415250D02*
G03*
X257810Y407811I0J-25400D01*
G01*
X223950Y384471D02*
G03*
X241910Y391910I0J25400D01*
G01*
X266954Y428129D02*
G03*
X284750Y435500I-0J25167D01*
G01*
X240792Y435734D02*
G03*
X248397Y428129I7605J0D01*
G01*
X292234Y438600D02*
G03*
X284750Y435500I0J-10584D01*
G01*
X389572Y412069D02*
G03*
X373371Y394531I0J-16252D01*
G01*
X478044Y435727D02*
G03*
X484750Y442432I0J6706D01*
G01*
X361241Y365241D02*
G03*
X373371Y394531I-29296J29290D01*
G01*
X363017Y465767D02*
G03*
X363018Y465768I-4267J4269D01*
G01*
X358750Y464000D02*
G03*
X363017Y465767I0J6036D01*
G01*
X392271Y484500D02*
G03*
X374310Y477061I0J-25400D01*
G01*
X476750Y480500D02*
G03*
X467093Y484500I-9657J-9657D01*
G01*
X484750Y465068D02*
G03*
X479495Y477755I-17943J0D01*
G01*
X273620Y280120D02*
G03*
X273500Y279830I291J-291D01*
G01*
X310440Y422690D02*
X317300Y429550D01*
X234398Y422690D02*
X310440D01*
X238500Y419000D02*
X325000D01*
X223373Y415288D02*
X234788D01*
X238500Y419000D01*
X330000Y424000D02*
Y432550D01*
X325000Y419000D02*
X330000Y424000D01*
X317300Y429550D02*
Y432550D01*
X132750Y349495D02*
Y443648D01*
X298715Y489190D02*
X298775Y489250D01*
X308750D01*
X343250Y488750D02*
X351500D01*
X330000Y470050D02*
Y483500D01*
X335250Y488750D01*
X317300Y470050D02*
Y488700D01*
X316750Y489250D02*
X317300Y488700D01*
X445113Y433439D02*
X447400Y435726D01*
X384021Y426000D02*
X427153D01*
X366000Y418500D02*
X366060Y418560D01*
X275771Y415250D02*
X358154D01*
X241910Y391910D02*
X257810Y407811D01*
X167947Y384471D02*
X223950D01*
X457000Y421676D02*
Y435727D01*
X248397Y428129D02*
X266954D01*
X240792Y435734D02*
Y457200D01*
X292234Y438600D02*
X301250D01*
X389572Y412069D02*
X389572D01*
X456993D02*
X457000Y412076D01*
X389572Y412069D02*
X456993D01*
X254255Y161005D02*
Y178804D01*
X244500Y151250D02*
X254255Y161005D01*
Y178804D02*
X258157Y182705D01*
X241500Y157000D02*
X248323Y163822D01*
X243939Y182955D02*
X248323Y178571D01*
Y163822D02*
Y178571D01*
X258157Y182705D02*
X258939D01*
X206500Y157000D02*
X241500D01*
X199500Y164000D02*
X206500Y157000D01*
X195000Y160988D02*
X204738Y151250D01*
X244500D01*
X484750Y442432D02*
Y465068D01*
X473649Y435727D02*
X478044D01*
X363017Y465767D02*
X363018Y465768D01*
X374310Y477061D01*
X392271Y484500D02*
X467093D01*
X476750Y480500D02*
X479495Y477755D01*
X457000Y435727D02*
Y457000D01*
Y435727D02*
X466849D01*
X315250Y319250D02*
X361241Y365241D01*
X302280Y306280D02*
X315250Y319250D01*
X300250Y305000D02*
X302280Y306280D01*
X273620Y280120D02*
X290932Y297432D01*
X293462Y298212D01*
X273500Y274811D02*
Y279830D01*
X132750Y349495D02*
X145500Y336745D01*
X120500Y455899D02*
X132750Y443648D01*
X128250Y345971D02*
Y440750D01*
Y345971D02*
X140318Y333903D01*
X120500Y455899D02*
Y460258D01*
X123750Y463508D01*
X116250Y452750D02*
X128250Y440750D01*
X116250Y452750D02*
Y459508D01*
X112250Y463508D02*
X116250Y459508D01*
X120500Y466758D02*
Y472500D01*
Y466758D02*
X123750Y463508D01*
X112250D02*
X116000Y467258D01*
Y471787D01*
X145500Y302550D02*
Y336745D01*
X151739Y296311D02*
X159000D01*
X145500Y302550D02*
X151739Y296311D01*
X171447Y333571D02*
X187329Y317689D01*
X187358D02*
X190250Y314796D01*
X167947Y333571D02*
X171447D01*
X187329Y317689D02*
X187358D01*
X140318Y298644D02*
Y333903D01*
X148747Y290214D02*
X157812D01*
X140318Y298644D02*
X148747Y290214D01*
X199500Y164000D02*
Y238610D01*
X195000Y160988D02*
Y233855D01*
X184474Y244381D02*
X195000Y233855D01*
X190250Y247860D02*
X199500Y238610D01*
X190250Y247860D02*
Y314796D01*
X180937Y244381D02*
X184474D01*
X167947Y257371D02*
X180937Y244381D01*
X167947Y305258D02*
Y333571D01*
X159000Y296311D02*
X167947Y305258D01*
Y257371D02*
Y280080D01*
X157812Y290214D02*
X167947Y280080D01*
X102000Y484000D02*
X103787D01*
X116000Y471787D01*
X120500Y472500D02*
X132000Y484000D01*
X403000Y274431D02*
Y295311D01*
X403000Y185091D02*
Y206311D01*
D69*
X258500Y210803D02*
G03*
X258939Y209744I1497J0D01*
G01*
X243500Y210803D02*
G03*
X243939Y209744I1498J0D01*
G01*
X258500Y210803D02*
Y226811D01*
X243500Y210803D02*
Y226811D01*
D70*
X16836Y491645D02*
D03*
X492909Y492701D02*
D03*
X492478Y15188D02*
D03*
D71*
X240792Y464000D02*
X241146Y464354D01*
Y478396D01*
X241500Y478750D01*
X255250Y464050D02*
X301250D01*
X240792Y464000D02*
X255200D01*
X255250Y464050D01*
X301250Y464000D02*
Y464050D01*
D72*
X228500Y209744D02*
Y226811D01*
X228424Y209744D02*
X228500D01*
X69000Y463250D02*
X69258Y463508D01*
X104250D01*
X391028Y373552D02*
X401947Y384471D01*
X391028Y361264D02*
Y373552D01*
X402268Y384149D02*
X431167D01*
X401947Y384471D02*
X402268Y384149D01*
X131750Y463508D02*
X139750D01*
X228500Y274811D02*
X243500D01*
X228500Y274811D02*
X228500Y274811D01*
X213500Y196772D02*
Y229311D01*
D73*
X224129Y188721D02*
Y195743D01*
X223100Y196772D02*
X224129Y195743D01*
D74*
X243500Y257561D02*
Y274811D01*
X243500Y274811D01*
X243500Y274811D02*
X244245Y275556D01*
Y292311D01*
X243500Y274811D02*
X243500Y274811D01*
D75*
X311662Y259499D02*
X311824Y259661D01*
X315000Y203311D02*
X315162Y203473D01*
D76*
X34250Y179000D02*
D03*
D77*
X59650D02*
D03*
D78*
X192000Y484000D02*
D03*
X51000Y457000D02*
D03*
X457000Y51000D02*
D03*
Y457000D02*
D03*
X132000Y484000D02*
D03*
X102000D02*
D03*
X72000D02*
D03*
X457000Y254000D02*
D03*
X51000Y51000D02*
D03*
X162000Y484000D02*
D03*
D79*
X465000Y138000D02*
D03*
Y349000D02*
D03*
D80*
X315000Y203311D02*
D03*
X241500Y478750D02*
D03*
X220968Y339000D02*
D03*
X349911Y39320D02*
D03*
X350161Y52070D02*
D03*
X350607Y63513D02*
D03*
X350161Y75070D02*
D03*
X360411Y74570D02*
D03*
X360857Y63014D02*
D03*
X360411Y51570D02*
D03*
X360161Y38820D02*
D03*
X350911Y90320D02*
D03*
X351161Y103070D02*
D03*
X351607Y114514D02*
D03*
X351161Y126070D02*
D03*
X361411Y125570D02*
D03*
X361857Y114014D02*
D03*
X361411Y102570D02*
D03*
X361161Y89820D02*
D03*
X308000Y46100D02*
D03*
X320750Y45850D02*
D03*
X332193Y45405D02*
D03*
X343750Y45850D02*
D03*
X343250Y35600D02*
D03*
X331693Y35155D02*
D03*
X320250Y35600D02*
D03*
X307500Y35850D02*
D03*
Y84500D02*
D03*
X320250Y84250D02*
D03*
X331693Y83804D02*
D03*
X343250Y84250D02*
D03*
X342750Y74000D02*
D03*
X331194Y73554D02*
D03*
X319750Y74000D02*
D03*
X307000Y74250D02*
D03*
X306320Y53339D02*
D03*
X319070Y53089D02*
D03*
X330513Y52643D02*
D03*
X342070Y53089D02*
D03*
X342570Y63339D02*
D03*
X331013Y62893D02*
D03*
X319570Y63339D02*
D03*
X306820Y63589D02*
D03*
Y105339D02*
D03*
X319570Y105089D02*
D03*
X331013Y104643D02*
D03*
X342570Y105089D02*
D03*
X342070Y94839D02*
D03*
X330513Y94393D02*
D03*
X319070Y94839D02*
D03*
X306320Y95089D02*
D03*
X307000Y116000D02*
D03*
X319750Y115750D02*
D03*
X331194Y115304D02*
D03*
X342750Y115750D02*
D03*
X343250Y126000D02*
D03*
X331693Y125554D02*
D03*
X320250Y126000D02*
D03*
X307500Y126250D02*
D03*
X192905Y69250D02*
D03*
X183138Y69052D02*
D03*
X173250Y65020D02*
D03*
X161750Y64750D02*
D03*
X149500Y63250D02*
D03*
X234398Y422690D02*
D03*
X223373Y415288D02*
D03*
X298715Y489190D02*
D03*
X351500Y488750D02*
D03*
X445113Y472750D02*
D03*
X475000Y447750D02*
D03*
X331500Y400274D02*
D03*
X327000Y392924D02*
D03*
X342703Y406495D02*
D03*
X206542Y332843D02*
D03*
X193292Y330805D02*
D03*
X145000Y264000D02*
D03*
X156752Y276869D02*
D03*
X83952Y262552D02*
D03*
X17462Y347587D02*
D03*
X363500Y449682D02*
D03*
X241197Y308750D02*
D03*
X285250Y446030D02*
D03*
X372500Y440000D02*
D03*
X440352Y374949D02*
D03*
X294500Y454750D02*
D03*
X270921Y437500D02*
D03*
X267761Y319250D02*
D03*
X172000Y147750D02*
D03*
X158750Y132850D02*
D03*
X52118Y197290D02*
D03*
X65473Y198873D02*
D03*
X65619Y215500D02*
D03*
X66659Y224000D02*
D03*
X87000Y475250D02*
D03*
X117080Y493963D02*
D03*
X177000Y492750D02*
D03*
X209500Y489750D02*
D03*
X444999Y421418D02*
D03*
X69000Y463250D02*
D03*
X289250Y269500D02*
D03*
X343677Y360775D02*
D03*
X391028Y361264D02*
D03*
X354750Y339500D02*
D03*
X363284Y389088D02*
D03*
X259492Y353693D02*
D03*
X274414Y352344D02*
D03*
X334750Y326000D02*
D03*
X297250Y385500D02*
D03*
X228424Y209744D02*
D03*
X224129Y188721D02*
D03*
X243500Y244381D02*
D03*
X212000Y174955D02*
D03*
X159750Y177787D02*
D03*
X171400Y173000D02*
D03*
X258939Y182705D02*
D03*
X243939Y182955D02*
D03*
X270189Y187644D02*
D03*
X258939Y209744D02*
D03*
X243939D02*
D03*
X279206Y190705D02*
D03*
X315250Y392363D02*
D03*
X345269Y393919D02*
D03*
X169161Y102103D02*
D03*
X183138D02*
D03*
X172498Y113250D02*
D03*
X95610Y353378D02*
D03*
X184407Y173689D02*
D03*
X146750Y230310D02*
D03*
X350250Y211521D02*
D03*
X344750Y243000D02*
D03*
X332000D02*
D03*
X243500Y257561D02*
D03*
X293674Y244381D02*
D03*
X206956Y397805D02*
D03*
X207706Y432800D02*
D03*
X175750D02*
D03*
X51500Y390689D02*
D03*
X103750Y358378D02*
D03*
X142000Y359750D02*
D03*
X109250Y377668D02*
D03*
X139750Y463508D02*
D03*
X17785Y397960D02*
D03*
X17500Y388019D02*
D03*
Y377710D02*
D03*
Y367710D02*
D03*
Y357460D02*
D03*
X8744Y354901D02*
D03*
X244245Y292311D02*
D03*
X393250Y242500D02*
D03*
X272892Y294750D02*
D03*
X55967Y354628D02*
D03*
X27078Y93504D02*
D03*
X129610Y95565D02*
D03*
X55090Y93504D02*
D03*
X91000Y108500D02*
D03*
X391579Y185091D02*
D03*
X403000Y173750D02*
D03*
Y263500D02*
D03*
X414482Y274431D02*
D03*
X273500Y244381D02*
D03*
X258000D02*
D03*
Y292250D02*
D03*
X363962Y297432D02*
D03*
X232250Y291385D02*
D03*
X264500Y375775D02*
D03*
X375750Y322588D02*
D03*
X145319Y249000D02*
D03*
X160000Y186500D02*
D03*
X84365Y251500D02*
D03*
X22702Y246500D02*
D03*
X52108Y254060D02*
D03*
X102727Y162527D02*
D03*
X66500D02*
D03*
X77704D02*
D03*
X115250D02*
D03*
X142000Y178086D02*
D03*
X130429Y181250D02*
D03*
X114250Y104000D02*
D03*
X72036Y102261D02*
D03*
X41916Y93504D02*
D03*
X55090Y106500D02*
D03*
X91005Y119250D02*
D03*
X129500Y106500D02*
D03*
X403000Y185091D02*
D03*
X403000Y274431D02*
D03*
M02*
